FILE_TYPE = MACRO_DRAWING;
SET COLOR_WIRE YELLOW;
SET COLOR_PROP ORANGE;
SET COLOR_DOT WHITE;
SET COLOR_ARC YELLOW;
SET COLOR_BODY GREEN;
SET COLOR_NOTE PURPLE;
SET PROP_DISPLAY VALUE;
SET PAGE_NUMBER P335;
FORCEADD UNIVERSAL_GND..1
(-4300 1500);
FORCEPROP 3 LASTPIN (-4300 1550) SIG_NAME GND\g
J 0
(-4290 1560);
DISPLAY 0.659574 (-4290 1560);
PAINT MONO (-4290 1560);
DISPLAY INVISIBLE (-4290 1560);
FORCEPROP 2 LAST ROOM IO_SLOT
J 1
(-4525 1575);
DISPLAY 0.744681 (-4525 1575);
FORCEPROP 2 LAST CDS_LIB pure_quanta_power
J 0
(-4300 1500);
PAINT MONO (-4300 1500);
DISPLAY INVISIBLE (-4300 1500);
FORCEPROP 1 LAST HDL_POWER GND
J 1
(-4275 1425);
DISPLAY 0.872340 (-4275 1425);
PAINT GREEN (-4275 1425);
DISPLAY INVISIBLE (-4275 1425);
FORCEPROP 1 LAST PATH I1
J 0
(-4225 1500);
DISPLAY 0.872340 (-4225 1500);
PAINT AQUA (-4225 1500);
DISPLAY INVISIBLE (-4225 1500);
FORCEADD OFFPAGE..5
(-4050 7100);
FORCEPROP 2 LAST $XR2 132 
J 0
(-4545 7100);
DISPLAY 0.638298 (-4545 7100);
PAINT MONO (-4545 7100);
FORCEPROP 2 LAST $XR1 82 
J 0
(-4425 7100);
DISPLAY 0.638298 (-4425 7100);
PAINT MONO (-4425 7100);
FORCEPROP 2 LAST $XR0 131 
J 0
(-4335 7100);
DISPLAY 0.638298 (-4335 7100);
PAINT MONO (-4335 7100);
FORCEPROP 2 LAST CDS_LIB standard
J 0
(-4050 7100);
DISPLAY INVISIBLE (-4050 7100);
FORCEPROP 1 LAST OFFPAGE TRUE
J 0
(-3725 6975);
DISPLAY 0.872340 (-3725 6975);
PAINT GREEN (-3725 6975);
DISPLAY INVISIBLE (-3725 6975);
FORCEPROP 1 LAST COMMENT_BODY TRUE
J 0
(-3950 7025);
DISPLAY 0.872340 (-3950 7025);
PAINT GREEN (-3950 7025);
DISPLAY INVISIBLE (-3950 7025);
FORCEPROP 2 LAST PATH I10
J 0
(-4300 7150);
DISPLAY 0.680851 (-4300 7150);
DISPLAY INVISIBLE (-4300 7150);
FORCEADD TAP..1
(925 3350);
FORCEPROP 3 LASTPIN (875 3350) SIG_NAME P5E_CPU0_G3_RX_DN<12>
J 0
(885 3360);
DISPLAY 0.659574 (885 3360);
PAINT MONO (885 3360);
DISPLAY INVISIBLE (885 3360);
FORCEPROP 1 LASTPIN (875 3350) BN 12
J 0
(863 3358);
DISPLAY 0.680851 (863 3358);
PAINT GREEN (863 3358);
FORCEPROP 2 LAST CDS_LIB standard
J 0
(925 3350);
PAINT MONO (925 3350);
DISPLAY INVISIBLE (925 3350);
FORCEPROP 1 LAST BODY_TYPE PLUMBING
J 0
(925 3400);
DISPLAY 0.872340 (925 3400);
PAINT GREEN (925 3400);
DISPLAY INVISIBLE (925 3400);
FORCEPROP 1 LAST HDL_TAP TRUE
J 0
(1250 3225);
DISPLAY 0.872340 (1250 3225);
PAINT GREEN (1250 3225);
DISPLAY INVISIBLE (1250 3225);
FORCEPROP 1 LAST PATH I100
J 0
(923 3350);
DISPLAY 0.872340 (923 3350);
PAINT GREEN (923 3350);
DISPLAY INVISIBLE (923 3350);
FORCEADD TAP..1
(925 3500);
FORCEPROP 3 LASTPIN (875 3500) SIG_NAME P5E_CPU0_G3_RX_DN<11>
J 0
(885 3510);
DISPLAY 0.659574 (885 3510);
PAINT MONO (885 3510);
DISPLAY INVISIBLE (885 3510);
FORCEPROP 1 LASTPIN (875 3500) BN 11
J 0
(863 3508);
DISPLAY 0.680851 (863 3508);
PAINT GREEN (863 3508);
FORCEPROP 2 LAST CDS_LIB standard
J 0
(925 3500);
PAINT MONO (925 3500);
DISPLAY INVISIBLE (925 3500);
FORCEPROP 1 LAST BODY_TYPE PLUMBING
J 0
(925 3550);
DISPLAY 0.872340 (925 3550);
PAINT GREEN (925 3550);
DISPLAY INVISIBLE (925 3550);
FORCEPROP 1 LAST HDL_TAP TRUE
J 0
(1250 3375);
DISPLAY 0.872340 (1250 3375);
PAINT GREEN (1250 3375);
DISPLAY INVISIBLE (1250 3375);
FORCEPROP 1 LAST PATH I101
J 0
(923 3500);
DISPLAY 0.872340 (923 3500);
PAINT GREEN (923 3500);
DISPLAY INVISIBLE (923 3500);
FORCEADD TAP..1
(775 3600);
FORCEPROP 3 LASTPIN (725 3600) SIG_NAME P5E_CPU0_G3_RX_DP<10>
J 0
(735 3610);
DISPLAY 0.659574 (735 3610);
PAINT MONO (735 3610);
DISPLAY INVISIBLE (735 3610);
FORCEPROP 1 LASTPIN (725 3600) BN 10
J 0
(713 3608);
DISPLAY 0.680851 (713 3608);
PAINT GREEN (713 3608);
FORCEPROP 2 LAST CDS_LIB standard
J 0
(775 3600);
PAINT MONO (775 3600);
DISPLAY INVISIBLE (775 3600);
FORCEPROP 1 LAST BODY_TYPE PLUMBING
J 0
(775 3650);
DISPLAY 0.872340 (775 3650);
PAINT GREEN (775 3650);
DISPLAY INVISIBLE (775 3650);
FORCEPROP 1 LAST HDL_TAP TRUE
J 0
(1100 3475);
DISPLAY 0.872340 (1100 3475);
PAINT GREEN (1100 3475);
DISPLAY INVISIBLE (1100 3475);
FORCEPROP 1 LAST PATH I102
J 0
(773 3600);
DISPLAY 0.872340 (773 3600);
PAINT GREEN (773 3600);
DISPLAY INVISIBLE (773 3600);
FORCEADD TAP..1
(775 3750);
FORCEPROP 3 LASTPIN (725 3750) SIG_NAME P5E_CPU0_G3_RX_DP<9>
J 0
(735 3760);
DISPLAY 0.659574 (735 3760);
PAINT MONO (735 3760);
DISPLAY INVISIBLE (735 3760);
FORCEPROP 1 LASTPIN (725 3750) BN 9
J 0
(713 3758);
DISPLAY 0.680851 (713 3758);
PAINT GREEN (713 3758);
FORCEPROP 2 LAST CDS_LIB standard
J 0
(775 3750);
PAINT MONO (775 3750);
DISPLAY INVISIBLE (775 3750);
FORCEPROP 1 LAST BODY_TYPE PLUMBING
J 0
(775 3800);
DISPLAY 0.872340 (775 3800);
PAINT GREEN (775 3800);
DISPLAY INVISIBLE (775 3800);
FORCEPROP 1 LAST HDL_TAP TRUE
J 0
(1100 3625);
DISPLAY 0.872340 (1100 3625);
PAINT GREEN (1100 3625);
DISPLAY INVISIBLE (1100 3625);
FORCEPROP 1 LAST PATH I103
J 0
(773 3750);
DISPLAY 0.872340 (773 3750);
PAINT GREEN (773 3750);
DISPLAY INVISIBLE (773 3750);
FORCEADD TAP..1
(775 3900);
FORCEPROP 3 LASTPIN (725 3900) SIG_NAME P5E_CPU0_G3_RX_DP<8>
J 0
(735 3910);
DISPLAY 0.659574 (735 3910);
PAINT MONO (735 3910);
DISPLAY INVISIBLE (735 3910);
FORCEPROP 1 LASTPIN (725 3900) BN 8
J 0
(713 3908);
DISPLAY 0.680851 (713 3908);
PAINT GREEN (713 3908);
FORCEPROP 2 LAST CDS_LIB standard
J 0
(775 3900);
PAINT MONO (775 3900);
DISPLAY INVISIBLE (775 3900);
FORCEPROP 1 LAST BODY_TYPE PLUMBING
J 0
(775 3950);
DISPLAY 0.872340 (775 3950);
PAINT GREEN (775 3950);
DISPLAY INVISIBLE (775 3950);
FORCEPROP 1 LAST HDL_TAP TRUE
J 0
(1100 3775);
DISPLAY 0.872340 (1100 3775);
PAINT GREEN (1100 3775);
DISPLAY INVISIBLE (1100 3775);
FORCEPROP 1 LAST PATH I104
J 0
(773 3900);
DISPLAY 0.872340 (773 3900);
PAINT GREEN (773 3900);
DISPLAY INVISIBLE (773 3900);
FORCEADD TAP..1
(925 3650);
FORCEPROP 3 LASTPIN (875 3650) SIG_NAME P5E_CPU0_G3_RX_DN<10>
J 0
(885 3660);
DISPLAY 0.659574 (885 3660);
PAINT MONO (885 3660);
DISPLAY INVISIBLE (885 3660);
FORCEPROP 1 LASTPIN (875 3650) BN 10
J 0
(863 3658);
DISPLAY 0.680851 (863 3658);
PAINT GREEN (863 3658);
FORCEPROP 2 LAST CDS_LIB standard
J 0
(925 3650);
PAINT MONO (925 3650);
DISPLAY INVISIBLE (925 3650);
FORCEPROP 1 LAST BODY_TYPE PLUMBING
J 0
(925 3700);
DISPLAY 0.872340 (925 3700);
PAINT GREEN (925 3700);
DISPLAY INVISIBLE (925 3700);
FORCEPROP 1 LAST HDL_TAP TRUE
J 0
(1250 3525);
DISPLAY 0.872340 (1250 3525);
PAINT GREEN (1250 3525);
DISPLAY INVISIBLE (1250 3525);
FORCEPROP 1 LAST PATH I105
J 0
(923 3650);
DISPLAY 0.872340 (923 3650);
PAINT GREEN (923 3650);
DISPLAY INVISIBLE (923 3650);
FORCEADD TAP..1
(925 3800);
FORCEPROP 3 LASTPIN (875 3800) SIG_NAME P5E_CPU0_G3_RX_DN<9>
J 0
(885 3810);
DISPLAY 0.659574 (885 3810);
PAINT MONO (885 3810);
DISPLAY INVISIBLE (885 3810);
FORCEPROP 1 LASTPIN (875 3800) BN 9
J 0
(863 3808);
DISPLAY 0.680851 (863 3808);
PAINT GREEN (863 3808);
FORCEPROP 2 LAST CDS_LIB standard
J 0
(925 3800);
PAINT MONO (925 3800);
DISPLAY INVISIBLE (925 3800);
FORCEPROP 1 LAST BODY_TYPE PLUMBING
J 0
(925 3850);
DISPLAY 0.872340 (925 3850);
PAINT GREEN (925 3850);
DISPLAY INVISIBLE (925 3850);
FORCEPROP 1 LAST HDL_TAP TRUE
J 0
(1250 3675);
DISPLAY 0.872340 (1250 3675);
PAINT GREEN (1250 3675);
DISPLAY INVISIBLE (1250 3675);
FORCEPROP 1 LAST PATH I106
J 0
(923 3800);
DISPLAY 0.872340 (923 3800);
PAINT GREEN (923 3800);
DISPLAY INVISIBLE (923 3800);
FORCEADD TAP..1
(925 3950);
FORCEPROP 3 LASTPIN (875 3950) SIG_NAME P5E_CPU0_G3_RX_DN<8>
J 0
(885 3960);
DISPLAY 0.659574 (885 3960);
PAINT MONO (885 3960);
DISPLAY INVISIBLE (885 3960);
FORCEPROP 1 LASTPIN (875 3950) BN 8
J 0
(863 3958);
DISPLAY 0.680851 (863 3958);
PAINT GREEN (863 3958);
FORCEPROP 2 LAST CDS_LIB standard
J 0
(925 3950);
PAINT MONO (925 3950);
DISPLAY INVISIBLE (925 3950);
FORCEPROP 1 LAST BODY_TYPE PLUMBING
J 0
(925 4000);
DISPLAY 0.872340 (925 4000);
PAINT GREEN (925 4000);
DISPLAY INVISIBLE (925 4000);
FORCEPROP 1 LAST HDL_TAP TRUE
J 0
(1250 3825);
DISPLAY 0.872340 (1250 3825);
PAINT GREEN (1250 3825);
DISPLAY INVISIBLE (1250 3825);
FORCEPROP 1 LAST PATH I107
J 0
(923 3950);
DISPLAY 0.872340 (923 3950);
PAINT GREEN (923 3950);
DISPLAY INVISIBLE (923 3950);
FORCEADD Q_RES..1
(1525 2700);
FORCEPROP 1 LAST LOCATION R46
J 0
(1250 2700);
DISPLAY 0.638298 (1250 2700);
FORCEPROP 2 LAST $SEC 1
J 0
(1475 2900);
DISPLAY 0.680851 (1475 2900);
PAINT MONO (1475 2900);
DISPLAY INVISIBLE (1475 2900);
FORCEPROP 2 LAST CDS_SEC 1
J 0
(1475 2900);
DISPLAY 1.021277 (1475 2900);
DISPLAY INVISIBLE (1475 2900);
FORCEPROP 1 LASTPIN (1425 2700) $PN 1
J 0
(1437 2712);
DISPLAY 0.787234 (1437 2712);
FORCEPROP 1 LASTPIN (1625 2700) $PN 2
J 0
(1587 2712);
DISPLAY 0.787234 (1587 2712);
FORCEPROP 1 LAST PACK_TYPE 0402LF
J 0
(1800 2700);
DISPLAY 0.638298 (1800 2700);
FORCEPROP 1 LAST TOLERANCE 5%
J 0
(1725 2700);
DISPLAY 0.638298 (1725 2700);
FORCEPROP 1 LAST VALUE 0
J 2
(1700 2700);
DISPLAY 0.638298 (1700 2700);
FORCEPROP 2 LAST CDS_LIB pure_quanta
J 0
(1525 2700);
PAINT MONO (1525 2700);
DISPLAY INVISIBLE (1525 2700);
FORCEPROP 1 LAST WATTAGE 1/16W
J 2
(1700 2825);
DISPLAY 0.638298 (1700 2825);
DISPLAY INVISIBLE (1700 2825);
FORCEPROP 1 LAST MATERIAL CHIP
J 0
(1400 2825);
DISPLAY 0.638298 (1400 2825);
DISPLAY INVISIBLE (1400 2825);
FORCEPROP 1 LAST PATH I108
J 0
(1475 2850);
DISPLAY 0.978723 (1475 2850);
PAINT WHITE (1475 2850);
DISPLAY INVISIBLE (1475 2850);
FORCEPROP 1 LAST PART_NUMBER CS00002JB13
J 0
(1400 2775);
DISPLAY 0.638298 (1400 2775);
DISPLAY INVISIBLE (1400 2775);
FORCEADD UNIVERSAL_GND..1
(2325 1400);
FORCEPROP 3 LASTPIN (2325 1450) SIG_NAME GND\g
J 0
(2335 1460);
DISPLAY 0.659574 (2335 1460);
PAINT MONO (2335 1460);
DISPLAY INVISIBLE (2335 1460);
FORCEPROP 2 LAST ROOM IO_SLOT
J 1
(2100 1475);
DISPLAY 0.744681 (2100 1475);
FORCEPROP 2 LAST CDS_LIB pure_quanta_power
J 0
(2325 1400);
PAINT MONO (2325 1400);
DISPLAY INVISIBLE (2325 1400);
FORCEPROP 1 LAST HDL_POWER GND
J 1
(2350 1325);
DISPLAY 0.872340 (2350 1325);
PAINT GREEN (2350 1325);
DISPLAY INVISIBLE (2350 1325);
FORCEPROP 1 LAST PATH I109
J 0
(2400 1400);
DISPLAY 0.872340 (2400 1400);
PAINT AQUA (2400 1400);
DISPLAY INVISIBLE (2400 1400);
FORCEADD UNIVERSAL_GND..1
(-3825 1500);
FORCEPROP 3 LASTPIN (-3825 1550) SIG_NAME GND\g
J 0
(-3815 1560);
DISPLAY 0.659574 (-3815 1560);
PAINT MONO (-3815 1560);
DISPLAY INVISIBLE (-3815 1560);
FORCEPROP 2 LAST ROOM IO_SLOT
J 1
(-4050 1575);
DISPLAY 0.744681 (-4050 1575);
FORCEPROP 2 LAST CDS_LIB pure_quanta_power
J 0
(-3825 1500);
PAINT MONO (-3825 1500);
DISPLAY INVISIBLE (-3825 1500);
FORCEPROP 1 LAST HDL_POWER GND
J 1
(-3800 1425);
DISPLAY 0.872340 (-3800 1425);
PAINT GREEN (-3800 1425);
DISPLAY INVISIBLE (-3800 1425);
FORCEPROP 1 LAST PATH I11
J 0
(-3750 1500);
DISPLAY 0.872340 (-3750 1500);
PAINT AQUA (-3750 1500);
DISPLAY INVISIBLE (-3750 1500);
FORCEADD Q_CAP..1
(2850 1900);
FORCEPROP 1 LAST LOCATION C1237
J 0
(2900 2000);
DISPLAY 0.787234 (2900 2000);
FORCEPROP 2 LAST $SEC 1
J 0
(2900 2100);
DISPLAY 0.680851 (2900 2100);
PAINT MONO (2900 2100);
DISPLAY INVISIBLE (2900 2100);
FORCEPROP 2 LAST CDS_SEC 1
J 0
(2900 2100);
DISPLAY 1.021277 (2900 2100);
DISPLAY INVISIBLE (2900 2100);
FORCEPROP 1 LASTPIN (2850 2000) $PN 1
J 0
(2860 1980);
DISPLAY 0.787234 (2860 1980);
FORCEPROP 1 LASTPIN (2850 1800) $PN 2
J 0
(2860 1780);
DISPLAY 0.787234 (2860 1780);
FORCEPROP 1 LAST MATERIAL X7R
J 0
(2900 1800);
DISPLAY 0.638298 (2900 1800);
FORCEPROP 1 LAST PACK_TYPE 0402
J 0
(2900 1750);
DISPLAY 0.638298 (2900 1750);
FORCEPROP 1 LAST TOLERANCE 10%
J 0
(2900 1850);
DISPLAY 0.638298 (2900 1850);
FORCEPROP 1 LAST VOLTAGE 25V
J 0
(2900 1900);
DISPLAY 0.638298 (2900 1900);
FORCEPROP 1 LAST VALUE 0.1UF
J 0
(2900 1950);
DISPLAY 0.638298 (2900 1950);
FORCEPROP 2 LAST CDS_LIB pure_quanta
J 0
(2850 1900);
PAINT MONO (2850 1900);
DISPLAY INVISIBLE (2850 1900);
FORCEPROP 1 LAST PATH I110
J 0
(2900 2050);
DISPLAY 0.978723 (2900 2050);
PAINT WHITE (2900 2050);
DISPLAY INVISIBLE (2900 2050);
FORCEPROP 1 LAST PART_NUMBER CH4104K1B00
J 0
(2900 1750);
DISPLAY 0.808511 (2900 1750);
DISPLAY INVISIBLE (2900 1750);
FORCEADD Q_CAP..1
(3100 1900);
FORCEPROP 1 LAST LOCATION C1238
J 0
(3150 2000);
DISPLAY 0.787234 (3150 2000);
FORCEPROP 2 LAST $SEC 1
J 0
(3150 2100);
DISPLAY 0.680851 (3150 2100);
PAINT MONO (3150 2100);
DISPLAY INVISIBLE (3150 2100);
FORCEPROP 2 LAST CDS_SEC 1
J 0
(3150 2100);
DISPLAY 1.021277 (3150 2100);
DISPLAY INVISIBLE (3150 2100);
FORCEPROP 1 LASTPIN (3100 2000) $PN 1
J 0
(3110 1980);
DISPLAY 0.787234 (3110 1980);
FORCEPROP 1 LASTPIN (3100 1800) $PN 2
J 0
(3110 1780);
DISPLAY 0.787234 (3110 1780);
FORCEPROP 1 LAST PACK_TYPE 0402
J 0
(3150 1750);
DISPLAY 0.638298 (3150 1750);
FORCEPROP 1 LAST VALUE 0.1UF
J 0
(3150 1950);
DISPLAY 0.638298 (3150 1950);
FORCEPROP 1 LAST VOLTAGE 25V
J 0
(3150 1900);
DISPLAY 0.638298 (3150 1900);
FORCEPROP 1 LAST TOLERANCE 10%
J 0
(3150 1850);
DISPLAY 0.638298 (3150 1850);
FORCEPROP 1 LAST MATERIAL X7R
J 0
(3150 1800);
DISPLAY 0.638298 (3150 1800);
FORCEPROP 2 LAST CDS_LIB pure_quanta
J 0
(3100 1900);
PAINT MONO (3100 1900);
DISPLAY INVISIBLE (3100 1900);
FORCEPROP 1 LAST PATH I111
J 0
(3150 2050);
DISPLAY 0.978723 (3150 2050);
PAINT WHITE (3150 2050);
DISPLAY INVISIBLE (3150 2050);
FORCEPROP 1 LAST PART_NUMBER CH4104K1B00
J 0
(3150 1750);
DISPLAY 0.808511 (3150 1750);
DISPLAY INVISIBLE (3150 1750);
FORCEADD Q_CAP..1
(3375 1900);
FORCEPROP 1 LAST LOCATION C1239
J 0
(3425 2000);
DISPLAY 0.787234 (3425 2000);
FORCEPROP 2 LAST $SEC 1
J 0
(3425 2100);
DISPLAY 0.680851 (3425 2100);
PAINT MONO (3425 2100);
DISPLAY INVISIBLE (3425 2100);
FORCEPROP 2 LAST CDS_SEC 1
J 0
(3425 2100);
DISPLAY 1.021277 (3425 2100);
DISPLAY INVISIBLE (3425 2100);
FORCEPROP 1 LASTPIN (3375 2000) $PN 1
J 0
(3385 1980);
DISPLAY 0.787234 (3385 1980);
FORCEPROP 1 LASTPIN (3375 1800) $PN 2
J 0
(3385 1780);
DISPLAY 0.787234 (3385 1780);
FORCEPROP 1 LAST VALUE 0.1UF
J 0
(3425 1950);
DISPLAY 0.638298 (3425 1950);
FORCEPROP 1 LAST VOLTAGE 25V
J 0
(3425 1900);
DISPLAY 0.638298 (3425 1900);
FORCEPROP 1 LAST TOLERANCE 10%
J 0
(3425 1850);
DISPLAY 0.638298 (3425 1850);
FORCEPROP 1 LAST PACK_TYPE 0402
J 0
(3425 1750);
DISPLAY 0.638298 (3425 1750);
FORCEPROP 1 LAST MATERIAL X7R
J 0
(3425 1800);
DISPLAY 0.638298 (3425 1800);
FORCEPROP 2 LAST CDS_LIB pure_quanta
J 0
(3375 1900);
PAINT MONO (3375 1900);
DISPLAY INVISIBLE (3375 1900);
FORCEPROP 1 LAST PATH I112
J 0
(3425 2050);
DISPLAY 0.978723 (3425 2050);
PAINT WHITE (3425 2050);
DISPLAY INVISIBLE (3425 2050);
FORCEPROP 1 LAST PART_NUMBER CH4104K1B00
J 0
(3425 1750);
DISPLAY 0.808511 (3425 1750);
DISPLAY INVISIBLE (3425 1750);
FORCEADD UNIVERSAL_GND..1
(3650 1550);
FORCEPROP 3 LASTPIN (3650 1600) SIG_NAME GND\g
J 0
(3660 1610);
DISPLAY 0.659574 (3660 1610);
PAINT MONO (3660 1610);
DISPLAY INVISIBLE (3660 1610);
FORCEPROP 2 LAST ROOM IO_SLOT
J 1
(3425 1625);
DISPLAY 0.744681 (3425 1625);
FORCEPROP 2 LAST CDS_LIB pure_quanta_power
J 0
(3650 1550);
PAINT MONO (3650 1550);
DISPLAY INVISIBLE (3650 1550);
FORCEPROP 1 LAST HDL_POWER GND
J 1
(3675 1475);
DISPLAY 0.872340 (3675 1475);
PAINT GREEN (3675 1475);
DISPLAY INVISIBLE (3675 1475);
FORCEPROP 1 LAST PATH I113
J 0
(3725 1550);
DISPLAY 0.872340 (3725 1550);
PAINT AQUA (3725 1550);
DISPLAY INVISIBLE (3725 1550);
FORCEADD Q_CAP..1
(3650 1900);
FORCEPROP 1 LAST LOCATION C1240
J 0
(3700 2000);
DISPLAY 0.787234 (3700 2000);
FORCEPROP 2 LAST $SEC 1
J 0
(3700 2100);
DISPLAY 0.680851 (3700 2100);
PAINT MONO (3700 2100);
DISPLAY INVISIBLE (3700 2100);
FORCEPROP 2 LAST CDS_SEC 1
J 0
(3700 2100);
DISPLAY 1.021277 (3700 2100);
DISPLAY INVISIBLE (3700 2100);
FORCEPROP 1 LASTPIN (3650 2000) $PN 1
J 0
(3660 1980);
DISPLAY 0.787234 (3660 1980);
FORCEPROP 1 LASTPIN (3650 1800) $PN 2
J 0
(3660 1780);
DISPLAY 0.787234 (3660 1780);
FORCEPROP 1 LAST VOLTAGE 25V
J 0
(3700 1900);
DISPLAY 0.638298 (3700 1900);
FORCEPROP 1 LAST TOLERANCE 10%
J 0
(3700 1850);
DISPLAY 0.638298 (3700 1850);
FORCEPROP 1 LAST MATERIAL X7R
J 0
(3700 1800);
DISPLAY 0.638298 (3700 1800);
FORCEPROP 1 LAST VALUE 0.1UF
J 0
(3700 1950);
DISPLAY 0.638298 (3700 1950);
FORCEPROP 1 LAST PACK_TYPE 0402
J 0
(3700 1750);
DISPLAY 0.638298 (3700 1750);
FORCEPROP 2 LAST CDS_LIB pure_quanta
J 0
(3650 1900);
PAINT MONO (3650 1900);
DISPLAY INVISIBLE (3650 1900);
FORCEPROP 1 LAST PATH I114
J 0
(3700 2050);
DISPLAY 0.978723 (3700 2050);
PAINT WHITE (3700 2050);
DISPLAY INVISIBLE (3700 2050);
FORCEPROP 1 LAST PART_NUMBER CH4104K1B00
J 0
(3700 1700);
DISPLAY 0.638298 (3700 1700);
DISPLAY INVISIBLE (3700 1700);
FORCEADD OFFPAGE..4
(2725 2750);
FORCEPROP 2 LAST $XR0 29 
J 0
(2911 2750);
DISPLAY 0.638298 (2911 2750);
PAINT MONO (2911 2750);
FORCEPROP 2 LAST CDS_LIB standard
J 0
(2725 2750);
PAINT MONO (2725 2750);
DISPLAY INVISIBLE (2725 2750);
FORCEPROP 1 LAST OFFPAGE TRUE
J 0
(3050 2625);
DISPLAY 0.872340 (3050 2625);
PAINT GREEN (3050 2625);
DISPLAY INVISIBLE (3050 2625);
FORCEPROP 1 LAST COMMENT_BODY TRUE
J 0
(2700 2650);
DISPLAY 0.872340 (2700 2650);
PAINT GREEN (2700 2650);
DISPLAY INVISIBLE (2700 2650);
FORCEPROP 2 LAST PATH I115
J 0
(2925 2800);
DISPLAY 0.680851 (2925 2800);
DISPLAY INVISIBLE (2925 2800);
FORCEADD OFFPAGE..4
(2725 2700);
FORCEPROP 2 LAST $XR0 29 
J 0
(2911 2700);
DISPLAY 0.638298 (2911 2700);
PAINT MONO (2911 2700);
FORCEPROP 2 LAST CDS_LIB standard
J 0
(2725 2700);
PAINT MONO (2725 2700);
DISPLAY INVISIBLE (2725 2700);
FORCEPROP 1 LAST OFFPAGE TRUE
J 0
(3050 2575);
DISPLAY 0.872340 (3050 2575);
PAINT GREEN (3050 2575);
DISPLAY INVISIBLE (3050 2575);
FORCEPROP 1 LAST COMMENT_BODY TRUE
J 0
(2700 2600);
DISPLAY 0.872340 (2700 2600);
PAINT GREEN (2700 2600);
DISPLAY INVISIBLE (2700 2600);
FORCEPROP 2 LAST PATH I116
J 0
(2925 2750);
DISPLAY 0.680851 (2925 2750);
DISPLAY INVISIBLE (2925 2750);
FORCEADD UNIVERSAL_POWER..1
(2850 2250);
FORCEPROP 3 LASTPIN (2850 2200) SIG_NAME P3V3_OCP_SFF\g
J 0
(2860 2210);
DISPLAY 0.659574 (2860 2210);
PAINT MONO (2860 2210);
DISPLAY INVISIBLE (2860 2210);
FORCEPROP 1 LAST HDL_POWER P3V3_OCP_SFF
J 1
(2850 2300);
DISPLAY 0.872340 (2850 2300);
PAINT GREEN (2850 2300);
FORCEPROP 2 LAST CDS_LIB pure_quanta_power
J 0
(2850 2250);
PAINT MONO (2850 2250);
DISPLAY INVISIBLE (2850 2250);
FORCEPROP 1 LAST PATH I117
J 0
(2900 2275);
DISPLAY 0.872340 (2900 2275);
PAINT AQUA (2900 2275);
DISPLAY INVISIBLE (2900 2275);
FORCEADD TAP..1
(775 4250);
FORCEPROP 3 LASTPIN (725 4250) SIG_NAME P5E_CPU0_G3_RX_DP<7>
J 0
(735 4260);
DISPLAY 0.659574 (735 4260);
PAINT MONO (735 4260);
DISPLAY INVISIBLE (735 4260);
FORCEPROP 1 LASTPIN (725 4250) BN 7
J 0
(713 4258);
DISPLAY 0.680851 (713 4258);
PAINT GREEN (713 4258);
FORCEPROP 2 LAST CDS_LIB standard
J 0
(775 4250);
PAINT MONO (775 4250);
DISPLAY INVISIBLE (775 4250);
FORCEPROP 1 LAST BODY_TYPE PLUMBING
J 0
(775 4300);
DISPLAY 0.872340 (775 4300);
PAINT GREEN (775 4300);
DISPLAY INVISIBLE (775 4300);
FORCEPROP 1 LAST HDL_TAP TRUE
J 0
(1100 4125);
DISPLAY 0.872340 (1100 4125);
PAINT GREEN (1100 4125);
DISPLAY INVISIBLE (1100 4125);
FORCEPROP 1 LAST PATH I118
J 0
(773 4250);
DISPLAY 0.872340 (773 4250);
PAINT GREEN (773 4250);
DISPLAY INVISIBLE (773 4250);
FORCEADD TAP..1
(775 4400);
FORCEPROP 3 LASTPIN (725 4400) SIG_NAME P5E_CPU0_G3_RX_DP<6>
J 0
(735 4410);
DISPLAY 0.659574 (735 4410);
PAINT MONO (735 4410);
DISPLAY INVISIBLE (735 4410);
FORCEPROP 1 LASTPIN (725 4400) BN 6
J 0
(713 4408);
DISPLAY 0.680851 (713 4408);
PAINT GREEN (713 4408);
FORCEPROP 2 LAST CDS_LIB standard
J 0
(775 4400);
PAINT MONO (775 4400);
DISPLAY INVISIBLE (775 4400);
FORCEPROP 1 LAST BODY_TYPE PLUMBING
J 0
(775 4450);
DISPLAY 0.872340 (775 4450);
PAINT GREEN (775 4450);
DISPLAY INVISIBLE (775 4450);
FORCEPROP 1 LAST HDL_TAP TRUE
J 0
(1100 4275);
DISPLAY 0.872340 (1100 4275);
PAINT GREEN (1100 4275);
DISPLAY INVISIBLE (1100 4275);
FORCEPROP 1 LAST PATH I119
J 0
(773 4400);
DISPLAY 0.872340 (773 4400);
PAINT GREEN (773 4400);
DISPLAY INVISIBLE (773 4400);
FORCEADD Q_RES..2
(-3825 1725);
FORCEPROP 1 LAST LOCATION R34
J 0
(-3780 1850);
DISPLAY 0.978723 (-3780 1850);
FORCEPROP 2 LAST $SEC 1
J 0
(-3775 1950);
DISPLAY 0.680851 (-3775 1950);
PAINT MONO (-3775 1950);
DISPLAY INVISIBLE (-3775 1950);
FORCEPROP 2 LAST CDS_SEC 1
J 0
(-3775 1950);
DISPLAY 1.021277 (-3775 1950);
DISPLAY INVISIBLE (-3775 1950);
FORCEPROP 1 LASTPIN (-3825 1825) $PN 1
J 0
(-3820 1787);
DISPLAY 0.787234 (-3820 1787);
FORCEPROP 1 LASTPIN (-3825 1625) $PN 2
J 0
(-3820 1635);
DISPLAY 0.787234 (-3820 1635);
FORCEPROP 1 LAST WATTAGE 1/16W
J 0
(-3785 1700);
DISPLAY 0.787234 (-3785 1700);
FORCEPROP 1 LAST TOLERANCE 1%
J 0
(-3780 1750);
DISPLAY 0.787234 (-3780 1750);
FORCEPROP 1 LAST PACK_TYPE 0402LF
J 0
(-3785 1550);
DISPLAY 0.787234 (-3785 1550);
FORCEPROP 1 LAST MATERIAL CHIP
J 0
(-3785 1650);
DISPLAY 0.787234 (-3785 1650);
FORCEPROP 1 LAST VALUE 4.7K
J 0
(-3780 1800);
DISPLAY 0.787234 (-3780 1800);
FORCEPROP 2 LAST CDS_LIB pure_quanta
J 0
(-3825 1725);
PAINT MONO (-3825 1725);
DISPLAY INVISIBLE (-3825 1725);
FORCEPROP 1 LAST PATH I12
J 0
(-3775 1900);
DISPLAY 0.978723 (-3775 1900);
PAINT WHITE (-3775 1900);
DISPLAY INVISIBLE (-3775 1900);
FORCEPROP 1 LAST PART_NUMBER CS24702FB06
J 0
(-3785 1600);
DISPLAY 0.787234 (-3785 1600);
DISPLAY INVISIBLE (-3785 1600);
FORCEADD TAP..1
(775 4550);
FORCEPROP 3 LASTPIN (725 4550) SIG_NAME P5E_CPU0_G3_RX_DP<5>
J 0
(735 4560);
DISPLAY 0.659574 (735 4560);
PAINT MONO (735 4560);
DISPLAY INVISIBLE (735 4560);
FORCEPROP 1 LASTPIN (725 4550) BN 5
J 0
(713 4558);
DISPLAY 0.680851 (713 4558);
PAINT GREEN (713 4558);
FORCEPROP 2 LAST CDS_LIB standard
J 0
(775 4550);
PAINT MONO (775 4550);
DISPLAY INVISIBLE (775 4550);
FORCEPROP 1 LAST BODY_TYPE PLUMBING
J 0
(775 4600);
DISPLAY 0.872340 (775 4600);
PAINT GREEN (775 4600);
DISPLAY INVISIBLE (775 4600);
FORCEPROP 1 LAST HDL_TAP TRUE
J 0
(1100 4425);
DISPLAY 0.872340 (1100 4425);
PAINT GREEN (1100 4425);
DISPLAY INVISIBLE (1100 4425);
FORCEPROP 1 LAST PATH I120
J 0
(773 4550);
DISPLAY 0.872340 (773 4550);
PAINT GREEN (773 4550);
DISPLAY INVISIBLE (773 4550);
FORCEADD TAP..1
(925 4300);
FORCEPROP 3 LASTPIN (875 4300) SIG_NAME P5E_CPU0_G3_RX_DN<7>
J 0
(885 4310);
DISPLAY 0.659574 (885 4310);
PAINT MONO (885 4310);
DISPLAY INVISIBLE (885 4310);
FORCEPROP 1 LASTPIN (875 4300) BN 7
J 0
(863 4308);
DISPLAY 0.680851 (863 4308);
PAINT GREEN (863 4308);
FORCEPROP 2 LAST CDS_LIB standard
J 0
(925 4300);
PAINT MONO (925 4300);
DISPLAY INVISIBLE (925 4300);
FORCEPROP 1 LAST BODY_TYPE PLUMBING
J 0
(925 4350);
DISPLAY 0.872340 (925 4350);
PAINT GREEN (925 4350);
DISPLAY INVISIBLE (925 4350);
FORCEPROP 1 LAST HDL_TAP TRUE
J 0
(1250 4175);
DISPLAY 0.872340 (1250 4175);
PAINT GREEN (1250 4175);
DISPLAY INVISIBLE (1250 4175);
FORCEPROP 1 LAST PATH I121
J 0
(923 4300);
DISPLAY 0.872340 (923 4300);
PAINT GREEN (923 4300);
DISPLAY INVISIBLE (923 4300);
FORCEADD TAP..1
(925 4600);
FORCEPROP 3 LASTPIN (875 4600) SIG_NAME P5E_CPU0_G3_RX_DN<5>
J 0
(885 4610);
DISPLAY 0.659574 (885 4610);
PAINT MONO (885 4610);
DISPLAY INVISIBLE (885 4610);
FORCEPROP 1 LASTPIN (875 4600) BN 5
J 0
(863 4608);
DISPLAY 0.680851 (863 4608);
PAINT GREEN (863 4608);
FORCEPROP 2 LAST CDS_LIB standard
J 0
(925 4600);
PAINT MONO (925 4600);
DISPLAY INVISIBLE (925 4600);
FORCEPROP 1 LAST BODY_TYPE PLUMBING
J 0
(925 4650);
DISPLAY 0.872340 (925 4650);
PAINT GREEN (925 4650);
DISPLAY INVISIBLE (925 4650);
FORCEPROP 1 LAST HDL_TAP TRUE
J 0
(1250 4475);
DISPLAY 0.872340 (1250 4475);
PAINT GREEN (1250 4475);
DISPLAY INVISIBLE (1250 4475);
FORCEPROP 1 LAST PATH I122
J 0
(923 4600);
DISPLAY 0.872340 (923 4600);
PAINT GREEN (923 4600);
DISPLAY INVISIBLE (923 4600);
FORCEADD TAP..1
(925 4450);
FORCEPROP 3 LASTPIN (875 4450) SIG_NAME P5E_CPU0_G3_RX_DN<6>
J 0
(885 4460);
DISPLAY 0.659574 (885 4460);
PAINT MONO (885 4460);
DISPLAY INVISIBLE (885 4460);
FORCEPROP 1 LASTPIN (875 4450) BN 6
J 0
(863 4458);
DISPLAY 0.680851 (863 4458);
PAINT GREEN (863 4458);
FORCEPROP 2 LAST CDS_LIB standard
J 0
(925 4450);
PAINT MONO (925 4450);
DISPLAY INVISIBLE (925 4450);
FORCEPROP 1 LAST BODY_TYPE PLUMBING
J 0
(925 4500);
DISPLAY 0.872340 (925 4500);
PAINT GREEN (925 4500);
DISPLAY INVISIBLE (925 4500);
FORCEPROP 1 LAST HDL_TAP TRUE
J 0
(1250 4325);
DISPLAY 0.872340 (1250 4325);
PAINT GREEN (1250 4325);
DISPLAY INVISIBLE (1250 4325);
FORCEPROP 1 LAST PATH I123
J 0
(923 4450);
DISPLAY 0.872340 (923 4450);
PAINT GREEN (923 4450);
DISPLAY INVISIBLE (923 4450);
FORCEADD TAP..1
(775 4700);
FORCEPROP 3 LASTPIN (725 4700) SIG_NAME P5E_CPU0_G3_RX_DP<4>
J 0
(735 4710);
DISPLAY 0.659574 (735 4710);
PAINT MONO (735 4710);
DISPLAY INVISIBLE (735 4710);
FORCEPROP 1 LASTPIN (725 4700) BN 4
J 0
(713 4708);
DISPLAY 0.680851 (713 4708);
PAINT GREEN (713 4708);
FORCEPROP 2 LAST CDS_LIB standard
J 0
(775 4700);
PAINT MONO (775 4700);
DISPLAY INVISIBLE (775 4700);
FORCEPROP 1 LAST BODY_TYPE PLUMBING
J 0
(775 4750);
DISPLAY 0.872340 (775 4750);
PAINT GREEN (775 4750);
DISPLAY INVISIBLE (775 4750);
FORCEPROP 1 LAST HDL_TAP TRUE
J 0
(1100 4575);
DISPLAY 0.872340 (1100 4575);
PAINT GREEN (1100 4575);
DISPLAY INVISIBLE (1100 4575);
FORCEPROP 1 LAST PATH I124
J 0
(773 4700);
DISPLAY 0.872340 (773 4700);
PAINT GREEN (773 4700);
DISPLAY INVISIBLE (773 4700);
FORCEADD TAP..1
(775 5000);
FORCEPROP 3 LASTPIN (725 5000) SIG_NAME P5E_CPU0_G3_RX_DP<3>
J 0
(735 5010);
DISPLAY 0.659574 (735 5010);
PAINT MONO (735 5010);
DISPLAY INVISIBLE (735 5010);
FORCEPROP 1 LASTPIN (725 5000) BN 3
J 0
(713 5008);
DISPLAY 0.680851 (713 5008);
PAINT GREEN (713 5008);
FORCEPROP 2 LAST CDS_LIB standard
J 0
(775 5000);
PAINT MONO (775 5000);
DISPLAY INVISIBLE (775 5000);
FORCEPROP 1 LAST BODY_TYPE PLUMBING
J 0
(775 5050);
DISPLAY 0.872340 (775 5050);
PAINT GREEN (775 5050);
DISPLAY INVISIBLE (775 5050);
FORCEPROP 1 LAST HDL_TAP TRUE
J 0
(1100 4875);
DISPLAY 0.872340 (1100 4875);
PAINT GREEN (1100 4875);
DISPLAY INVISIBLE (1100 4875);
FORCEPROP 1 LAST PATH I125
J 0
(773 5000);
DISPLAY 0.872340 (773 5000);
PAINT GREEN (773 5000);
DISPLAY INVISIBLE (773 5000);
FORCEADD TAP..1
(925 4750);
FORCEPROP 3 LASTPIN (875 4750) SIG_NAME P5E_CPU0_G3_RX_DN<4>
J 0
(885 4760);
DISPLAY 0.659574 (885 4760);
PAINT MONO (885 4760);
DISPLAY INVISIBLE (885 4760);
FORCEPROP 1 LASTPIN (875 4750) BN 4
J 0
(863 4758);
DISPLAY 0.680851 (863 4758);
PAINT GREEN (863 4758);
FORCEPROP 2 LAST CDS_LIB standard
J 0
(925 4750);
PAINT MONO (925 4750);
DISPLAY INVISIBLE (925 4750);
FORCEPROP 1 LAST BODY_TYPE PLUMBING
J 0
(925 4800);
DISPLAY 0.872340 (925 4800);
PAINT GREEN (925 4800);
DISPLAY INVISIBLE (925 4800);
FORCEPROP 1 LAST HDL_TAP TRUE
J 0
(1250 4625);
DISPLAY 0.872340 (1250 4625);
PAINT GREEN (1250 4625);
DISPLAY INVISIBLE (1250 4625);
FORCEPROP 1 LAST PATH I126
J 0
(923 4750);
DISPLAY 0.872340 (923 4750);
PAINT GREEN (923 4750);
DISPLAY INVISIBLE (923 4750);
FORCEADD TAP..1
(925 5050);
FORCEPROP 3 LASTPIN (875 5050) SIG_NAME P5E_CPU0_G3_RX_DN<3>
J 0
(885 5060);
DISPLAY 0.659574 (885 5060);
PAINT MONO (885 5060);
DISPLAY INVISIBLE (885 5060);
FORCEPROP 1 LASTPIN (875 5050) BN 3
J 0
(863 5058);
DISPLAY 0.680851 (863 5058);
PAINT GREEN (863 5058);
FORCEPROP 2 LAST CDS_LIB standard
J 0
(925 5050);
PAINT MONO (925 5050);
DISPLAY INVISIBLE (925 5050);
FORCEPROP 1 LAST BODY_TYPE PLUMBING
J 0
(925 5100);
DISPLAY 0.872340 (925 5100);
PAINT GREEN (925 5100);
DISPLAY INVISIBLE (925 5100);
FORCEPROP 1 LAST HDL_TAP TRUE
J 0
(1250 4925);
DISPLAY 0.872340 (1250 4925);
PAINT GREEN (1250 4925);
DISPLAY INVISIBLE (1250 4925);
FORCEPROP 1 LAST PATH I127
J 0
(923 5050);
DISPLAY 0.872340 (923 5050);
PAINT GREEN (923 5050);
DISPLAY INVISIBLE (923 5050);
FORCEADD TAP..1
(775 5150);
FORCEPROP 3 LASTPIN (725 5150) SIG_NAME P5E_CPU0_G3_RX_DP<2>
J 0
(735 5160);
DISPLAY 0.659574 (735 5160);
PAINT MONO (735 5160);
DISPLAY INVISIBLE (735 5160);
FORCEPROP 1 LASTPIN (725 5150) BN 2
J 0
(713 5158);
DISPLAY 0.680851 (713 5158);
PAINT GREEN (713 5158);
FORCEPROP 2 LAST CDS_LIB standard
J 0
(775 5150);
PAINT MONO (775 5150);
DISPLAY INVISIBLE (775 5150);
FORCEPROP 1 LAST BODY_TYPE PLUMBING
J 0
(775 5200);
DISPLAY 0.872340 (775 5200);
PAINT GREEN (775 5200);
DISPLAY INVISIBLE (775 5200);
FORCEPROP 1 LAST HDL_TAP TRUE
J 0
(1100 5025);
DISPLAY 0.872340 (1100 5025);
PAINT GREEN (1100 5025);
DISPLAY INVISIBLE (1100 5025);
FORCEPROP 1 LAST PATH I128
J 0
(773 5150);
DISPLAY 0.872340 (773 5150);
PAINT GREEN (773 5150);
DISPLAY INVISIBLE (773 5150);
FORCEADD TAP..1
(775 5300);
FORCEPROP 3 LASTPIN (725 5300) SIG_NAME P5E_CPU0_G3_RX_DP<1>
J 0
(735 5310);
DISPLAY 0.659574 (735 5310);
PAINT MONO (735 5310);
DISPLAY INVISIBLE (735 5310);
FORCEPROP 1 LASTPIN (725 5300) BN 1
J 0
(713 5308);
DISPLAY 0.680851 (713 5308);
PAINT GREEN (713 5308);
FORCEPROP 2 LAST CDS_LIB standard
J 0
(775 5300);
PAINT MONO (775 5300);
DISPLAY INVISIBLE (775 5300);
FORCEPROP 1 LAST BODY_TYPE PLUMBING
J 0
(775 5350);
DISPLAY 0.872340 (775 5350);
PAINT GREEN (775 5350);
DISPLAY INVISIBLE (775 5350);
FORCEPROP 1 LAST HDL_TAP TRUE
J 0
(1100 5175);
DISPLAY 0.872340 (1100 5175);
PAINT GREEN (1100 5175);
DISPLAY INVISIBLE (1100 5175);
FORCEPROP 1 LAST PATH I129
J 0
(773 5300);
DISPLAY 0.872340 (773 5300);
PAINT GREEN (773 5300);
DISPLAY INVISIBLE (773 5300);
FORCEADD OFFPAGE..5
(-1975 1450);
FORCEPROP 2 LAST $XR1 131 
J 0
(-2319 1450);
DISPLAY 0.638298 (-2319 1450);
PAINT MONO (-2319 1450);
FORCEPROP 2 LAST $XR0 80 
J 0
(-2199 1450);
DISPLAY 0.638298 (-2199 1450);
PAINT MONO (-2199 1450);
FORCEPROP 2 LAST CDS_LIB standard
J 0
(-1975 1450);
PAINT MONO (-1975 1450);
DISPLAY INVISIBLE (-1975 1450);
FORCEPROP 1 LAST OFFPAGE TRUE
J 0
(-1650 1325);
DISPLAY 0.872340 (-1650 1325);
PAINT GREEN (-1650 1325);
DISPLAY INVISIBLE (-1650 1325);
FORCEPROP 1 LAST COMMENT_BODY TRUE
J 0
(-1875 1375);
DISPLAY 0.872340 (-1875 1375);
PAINT GREEN (-1875 1375);
DISPLAY INVISIBLE (-1875 1375);
FORCEPROP 2 LAST PATH I13
J 0
(-2250 1500);
DISPLAY 0.680851 (-2250 1500);
DISPLAY INVISIBLE (-2250 1500);
FORCEADD TAP..1
(775 5450);
FORCEPROP 3 LASTPIN (725 5450) SIG_NAME P5E_CPU0_G3_RX_DP<0>
J 0
(735 5460);
DISPLAY 0.659574 (735 5460);
PAINT MONO (735 5460);
DISPLAY INVISIBLE (735 5460);
FORCEPROP 1 LASTPIN (725 5450) BN 0
J 0
(713 5458);
DISPLAY 0.680851 (713 5458);
PAINT GREEN (713 5458);
FORCEPROP 2 LAST CDS_LIB standard
J 0
(775 5450);
PAINT MONO (775 5450);
DISPLAY INVISIBLE (775 5450);
FORCEPROP 1 LAST BODY_TYPE PLUMBING
J 0
(775 5500);
DISPLAY 0.872340 (775 5500);
PAINT GREEN (775 5500);
DISPLAY INVISIBLE (775 5500);
FORCEPROP 1 LAST HDL_TAP TRUE
J 0
(1100 5325);
DISPLAY 0.872340 (1100 5325);
PAINT GREEN (1100 5325);
DISPLAY INVISIBLE (1100 5325);
FORCEPROP 1 LAST PATH I130
J 0
(773 5450);
DISPLAY 0.872340 (773 5450);
PAINT GREEN (773 5450);
DISPLAY INVISIBLE (773 5450);
FORCEADD TAP..1
(925 5200);
FORCEPROP 3 LASTPIN (875 5200) SIG_NAME P5E_CPU0_G3_RX_DN<2>
J 0
(885 5210);
DISPLAY 0.659574 (885 5210);
PAINT MONO (885 5210);
DISPLAY INVISIBLE (885 5210);
FORCEPROP 1 LASTPIN (875 5200) BN 2
J 0
(863 5208);
DISPLAY 0.680851 (863 5208);
PAINT GREEN (863 5208);
FORCEPROP 2 LAST CDS_LIB standard
J 0
(925 5200);
PAINT MONO (925 5200);
DISPLAY INVISIBLE (925 5200);
FORCEPROP 1 LAST BODY_TYPE PLUMBING
J 0
(925 5250);
DISPLAY 0.872340 (925 5250);
PAINT GREEN (925 5250);
DISPLAY INVISIBLE (925 5250);
FORCEPROP 1 LAST HDL_TAP TRUE
J 0
(1250 5075);
DISPLAY 0.872340 (1250 5075);
PAINT GREEN (1250 5075);
DISPLAY INVISIBLE (1250 5075);
FORCEPROP 1 LAST PATH I131
J 0
(923 5200);
DISPLAY 0.872340 (923 5200);
PAINT GREEN (923 5200);
DISPLAY INVISIBLE (923 5200);
FORCEADD TAP..1
(925 5350);
FORCEPROP 3 LASTPIN (875 5350) SIG_NAME P5E_CPU0_G3_RX_DN<1>
J 0
(885 5360);
DISPLAY 0.659574 (885 5360);
PAINT MONO (885 5360);
DISPLAY INVISIBLE (885 5360);
FORCEPROP 1 LASTPIN (875 5350) BN 1
J 0
(863 5358);
DISPLAY 0.680851 (863 5358);
PAINT GREEN (863 5358);
FORCEPROP 2 LAST CDS_LIB standard
J 0
(925 5350);
PAINT MONO (925 5350);
DISPLAY INVISIBLE (925 5350);
FORCEPROP 1 LAST BODY_TYPE PLUMBING
J 0
(925 5400);
DISPLAY 0.872340 (925 5400);
PAINT GREEN (925 5400);
DISPLAY INVISIBLE (925 5400);
FORCEPROP 1 LAST HDL_TAP TRUE
J 0
(1250 5225);
DISPLAY 0.872340 (1250 5225);
PAINT GREEN (1250 5225);
DISPLAY INVISIBLE (1250 5225);
FORCEPROP 1 LAST PATH I132
J 0
(923 5350);
DISPLAY 0.872340 (923 5350);
PAINT GREEN (923 5350);
DISPLAY INVISIBLE (923 5350);
FORCEADD TAP..1
(925 5500);
FORCEPROP 3 LASTPIN (875 5500) SIG_NAME P5E_CPU0_G3_RX_DN<0>
J 0
(885 5510);
DISPLAY 0.659574 (885 5510);
PAINT MONO (885 5510);
DISPLAY INVISIBLE (885 5510);
FORCEPROP 1 LASTPIN (875 5500) BN 0
J 0
(863 5508);
DISPLAY 0.680851 (863 5508);
PAINT GREEN (863 5508);
FORCEPROP 2 LAST CDS_LIB standard
J 0
(925 5500);
PAINT MONO (925 5500);
DISPLAY INVISIBLE (925 5500);
FORCEPROP 1 LAST BODY_TYPE PLUMBING
J 0
(925 5550);
DISPLAY 0.872340 (925 5550);
PAINT GREEN (925 5550);
DISPLAY INVISIBLE (925 5550);
FORCEPROP 1 LAST HDL_TAP TRUE
J 0
(1250 5375);
DISPLAY 0.872340 (1250 5375);
DISPLAY INVISIBLE (1250 5375);
FORCEPROP 1 LAST PATH I133
J 0
(923 5500);
DISPLAY 0.872340 (923 5500);
PAINT GREEN (923 5500);
DISPLAY INVISIBLE (923 5500);
FORCEADD OFFPAGE..2
(1975 4150);
FORCEPROP 2 LAST $XR1 143 
J 0
(2284 4150);
DISPLAY 0.638298 (2284 4150);
PAINT MONO (2284 4150);
FORCEPROP 2 LAST $XR0 134 
J 0
(2164 4150);
DISPLAY 0.638298 (2164 4150);
PAINT MONO (2164 4150);
FORCEPROP 2 LAST CDS_LIB standard
J 0
(1975 4150);
PAINT MONO (1975 4150);
DISPLAY INVISIBLE (1975 4150);
FORCEPROP 1 LAST OFFPAGE TRUE
J 0
(2300 4025);
DISPLAY 0.872340 (2300 4025);
PAINT GREEN (2300 4025);
DISPLAY INVISIBLE (2300 4025);
FORCEPROP 1 LAST COMMENT_BODY TRUE
J 0
(1930 4055);
DISPLAY 0.872340 (1930 4055);
PAINT GREEN (1930 4055);
DISPLAY INVISIBLE (1930 4055);
FORCEPROP 2 LAST PATH I134
J 0
(2300 4200);
DISPLAY 0.680851 (2300 4200);
DISPLAY INVISIBLE (2300 4200);
FORCEADD OFFPAGE..4
(1975 5600);
FORCEPROP 2 LAST $XR0 28 
J 0
(2161 5600);
DISPLAY 0.638298 (2161 5600);
PAINT MONO (2161 5600);
FORCEPROP 2 LAST CDS_LIB standard
J 0
(1975 5600);
PAINT MONO (1975 5600);
DISPLAY INVISIBLE (1975 5600);
FORCEPROP 1 LAST OFFPAGE TRUE
J 0
(2300 5475);
DISPLAY 0.872340 (2300 5475);
PAINT GREEN (2300 5475);
DISPLAY INVISIBLE (2300 5475);
FORCEPROP 1 LAST COMMENT_BODY TRUE
J 0
(1950 5500);
DISPLAY 0.872340 (1950 5500);
PAINT GREEN (1950 5500);
DISPLAY INVISIBLE (1950 5500);
FORCEPROP 2 LAST PATH I135
J 0
(2175 5650);
DISPLAY 0.680851 (2175 5650);
DISPLAY INVISIBLE (2175 5650);
FORCEADD OFFPAGE..2
(1975 5525);
FORCEPROP 2 LAST $XR0 23 
J 0
(2164 5525);
DISPLAY 0.638298 (2164 5525);
PAINT MONO (2164 5525);
FORCEPROP 2 LAST CDS_LIB standard
J 0
(1975 5525);
DISPLAY INVISIBLE (1975 5525);
FORCEPROP 1 LAST OFFPAGE TRUE
J 0
(2300 5400);
DISPLAY 0.872340 (2300 5400);
PAINT GREEN (2300 5400);
DISPLAY INVISIBLE (2300 5400);
FORCEPROP 1 LAST COMMENT_BODY TRUE
J 0
(1930 5430);
DISPLAY 0.872340 (1930 5430);
PAINT GREEN (1930 5430);
DISPLAY INVISIBLE (1930 5430);
FORCEPROP 2 LAST PATH I136
J 0
(2175 5575);
DISPLAY 0.680851 (2175 5575);
DISPLAY INVISIBLE (2175 5575);
FORCEADD OFFPAGE..2
(1975 5475);
FORCEPROP 2 LAST $XR0 23 
J 0
(2164 5475);
DISPLAY 0.638298 (2164 5475);
PAINT MONO (2164 5475);
FORCEPROP 2 LAST CDS_LIB standard
J 0
(1975 5475);
DISPLAY INVISIBLE (1975 5475);
FORCEPROP 1 LAST OFFPAGE TRUE
J 0
(2300 5350);
DISPLAY 0.872340 (2300 5350);
PAINT GREEN (2300 5350);
DISPLAY INVISIBLE (2300 5350);
FORCEPROP 1 LAST COMMENT_BODY TRUE
J 0
(1930 5380);
DISPLAY 0.872340 (1930 5380);
PAINT GREEN (1930 5380);
DISPLAY INVISIBLE (1930 5380);
FORCEPROP 2 LAST PATH I137
J 0
(2175 5525);
DISPLAY 0.680851 (2175 5525);
DISPLAY INVISIBLE (2175 5525);
FORCEADD OFFPAGE..4
(1975 5650);
FORCEPROP 2 LAST $XR0 28 
J 0
(2161 5650);
DISPLAY 0.638298 (2161 5650);
PAINT MONO (2161 5650);
FORCEPROP 2 LAST CDS_LIB standard
J 0
(1975 5650);
PAINT MONO (1975 5650);
DISPLAY INVISIBLE (1975 5650);
FORCEPROP 1 LAST OFFPAGE TRUE
J 0
(2300 5525);
DISPLAY 0.872340 (2300 5525);
PAINT GREEN (2300 5525);
DISPLAY INVISIBLE (2300 5525);
FORCEPROP 1 LAST COMMENT_BODY TRUE
J 0
(1950 5550);
DISPLAY 0.872340 (1950 5550);
PAINT GREEN (1950 5550);
DISPLAY INVISIBLE (1950 5550);
FORCEPROP 2 LAST PATH I138
J 0
(2175 5700);
DISPLAY 0.680851 (2175 5700);
DISPLAY INVISIBLE (2175 5700);
FORCEADD OFFPAGE..5
(-2000 1625);
FORCEPROP 2 LAST $XR1 80 
J 0
(-2375 1625);
DISPLAY 0.638298 (-2375 1625);
PAINT MONO (-2375 1625);
FORCEPROP 2 LAST $XR0 131 
J 0
(-2285 1625);
DISPLAY 0.638298 (-2285 1625);
PAINT MONO (-2285 1625);
FORCEPROP 2 LAST CDS_LIB standard
J 0
(-2000 1625);
PAINT MONO (-2000 1625);
DISPLAY INVISIBLE (-2000 1625);
FORCEPROP 1 LAST OFFPAGE TRUE
J 0
(-1675 1500);
DISPLAY 0.872340 (-1675 1500);
PAINT GREEN (-1675 1500);
DISPLAY INVISIBLE (-1675 1500);
FORCEPROP 1 LAST COMMENT_BODY TRUE
J 0
(-1900 1550);
DISPLAY 0.872340 (-1900 1550);
PAINT GREEN (-1900 1550);
DISPLAY INVISIBLE (-1900 1550);
FORCEPROP 2 LAST PATH I14
J 0
(-2275 1675);
DISPLAY 0.680851 (-2275 1675);
DISPLAY INVISIBLE (-2275 1675);
FORCEADD OFFPAGE..4
(1975 5800);
FORCEPROP 2 LAST $XR0 133 
J 0
(2161 5800);
DISPLAY 0.638298 (2161 5800);
PAINT MONO (2161 5800);
FORCEPROP 2 LAST CDS_LIB standard
J 0
(1975 5800);
PAINT MONO (1975 5800);
DISPLAY INVISIBLE (1975 5800);
FORCEPROP 1 LAST OFFPAGE TRUE
J 0
(2300 5675);
DISPLAY 0.872340 (2300 5675);
PAINT GREEN (2300 5675);
DISPLAY INVISIBLE (2300 5675);
FORCEPROP 1 LAST COMMENT_BODY TRUE
J 0
(1950 5700);
DISPLAY 0.872340 (1950 5700);
PAINT GREEN (1950 5700);
DISPLAY INVISIBLE (1950 5700);
FORCEPROP 2 LAST PATH I141
J 0
(2175 5850);
DISPLAY 0.680851 (2175 5850);
DISPLAY INVISIBLE (2175 5850);
FORCEADD OFFPAGE..4
(1975 5750);
FORCEPROP 2 LAST $XR1 143 
J 0
(2281 5750);
DISPLAY 0.638298 (2281 5750);
PAINT MONO (2281 5750);
FORCEPROP 2 LAST $XR0 134 
J 0
(2161 5750);
DISPLAY 0.638298 (2161 5750);
PAINT MONO (2161 5750);
FORCEPROP 2 LAST CDS_LIB standard
J 0
(1975 5750);
PAINT MONO (1975 5750);
DISPLAY INVISIBLE (1975 5750);
FORCEPROP 1 LAST OFFPAGE TRUE
J 0
(2300 5625);
DISPLAY 0.872340 (2300 5625);
PAINT GREEN (2300 5625);
DISPLAY INVISIBLE (2300 5625);
FORCEPROP 1 LAST COMMENT_BODY TRUE
J 0
(1950 5650);
DISPLAY 0.872340 (1950 5650);
PAINT GREEN (1950 5650);
DISPLAY INVISIBLE (1950 5650);
FORCEPROP 2 LAST PATH I142
J 0
(2300 5800);
DISPLAY 0.680851 (2300 5800);
DISPLAY INVISIBLE (2300 5800);
FORCEADD OFFPAGE..4
(1425 6450);
FORCEPROP 2 LAST $XR0 133 
J 0
(1611 6450);
DISPLAY 0.638298 (1611 6450);
PAINT MONO (1611 6450);
FORCEPROP 2 LAST CDS_LIB standard
J 0
(1425 6450);
PAINT MONO (1425 6450);
DISPLAY INVISIBLE (1425 6450);
FORCEPROP 1 LAST OFFPAGE TRUE
J 0
(1750 6325);
DISPLAY 0.872340 (1750 6325);
PAINT GREEN (1750 6325);
DISPLAY INVISIBLE (1750 6325);
FORCEPROP 1 LAST COMMENT_BODY TRUE
J 0
(1400 6350);
DISPLAY 0.872340 (1400 6350);
PAINT GREEN (1400 6350);
DISPLAY INVISIBLE (1400 6350);
FORCEPROP 2 LAST PATH I143
J 0
(1625 6500);
DISPLAY 0.680851 (1625 6500);
DISPLAY INVISIBLE (1625 6500);
FORCEADD OFFPAGE..4
(1425 6600);
FORCEPROP 2 LAST $XR0 28 
J 0
(1611 6600);
DISPLAY 0.638298 (1611 6600);
PAINT MONO (1611 6600);
FORCEPROP 2 LAST CDS_LIB standard
J 0
(1425 6600);
PAINT MONO (1425 6600);
DISPLAY INVISIBLE (1425 6600);
FORCEPROP 1 LAST OFFPAGE TRUE
J 0
(1750 6475);
DISPLAY 0.872340 (1750 6475);
PAINT GREEN (1750 6475);
DISPLAY INVISIBLE (1750 6475);
FORCEPROP 1 LAST COMMENT_BODY TRUE
J 0
(1400 6500);
DISPLAY 0.872340 (1400 6500);
PAINT GREEN (1400 6500);
DISPLAY INVISIBLE (1400 6500);
FORCEPROP 2 LAST PATH I144
J 0
(1625 6650);
DISPLAY 0.680851 (1625 6650);
DISPLAY INVISIBLE (1625 6650);
FORCEADD OFFPAGE..4
(1425 6550);
FORCEPROP 2 LAST $XR0 28 
J 0
(1611 6550);
DISPLAY 0.638298 (1611 6550);
PAINT MONO (1611 6550);
FORCEPROP 2 LAST CDS_LIB standard
J 0
(1425 6550);
PAINT MONO (1425 6550);
DISPLAY INVISIBLE (1425 6550);
FORCEPROP 1 LAST OFFPAGE TRUE
J 0
(1750 6425);
DISPLAY 0.872340 (1750 6425);
PAINT GREEN (1750 6425);
DISPLAY INVISIBLE (1750 6425);
FORCEPROP 1 LAST COMMENT_BODY TRUE
J 0
(1400 6450);
DISPLAY 0.872340 (1400 6450);
PAINT GREEN (1400 6450);
DISPLAY INVISIBLE (1400 6450);
FORCEPROP 2 LAST PATH I145
J 0
(1625 6600);
DISPLAY 0.680851 (1625 6600);
DISPLAY INVISIBLE (1625 6600);
FORCEADD OFFPAGE..4
(1425 6750);
FORCEPROP 2 LAST $XR0 132 
J 0
(1611 6750);
DISPLAY 0.638298 (1611 6750);
PAINT MONO (1611 6750);
FORCEPROP 2 LAST CDS_LIB standard
J 0
(1425 6750);
PAINT MONO (1425 6750);
DISPLAY INVISIBLE (1425 6750);
FORCEPROP 1 LAST OFFPAGE TRUE
J 0
(1750 6625);
DISPLAY 0.872340 (1750 6625);
PAINT GREEN (1750 6625);
DISPLAY INVISIBLE (1750 6625);
FORCEPROP 1 LAST COMMENT_BODY TRUE
J 0
(1400 6650);
DISPLAY 0.872340 (1400 6650);
PAINT GREEN (1400 6650);
DISPLAY INVISIBLE (1400 6650);
FORCEPROP 2 LAST PATH I146
J 0
(1625 6800);
DISPLAY 0.680851 (1625 6800);
DISPLAY INVISIBLE (1625 6800);
FORCEADD OFFPAGE..4
(1425 6700);
FORCEPROP 2 LAST $XR0 132 
J 0
(1611 6700);
DISPLAY 0.638298 (1611 6700);
PAINT MONO (1611 6700);
FORCEPROP 2 LAST CDS_LIB standard
J 0
(1425 6700);
PAINT MONO (1425 6700);
DISPLAY INVISIBLE (1425 6700);
FORCEPROP 1 LAST OFFPAGE TRUE
J 0
(1750 6575);
DISPLAY 0.872340 (1750 6575);
PAINT GREEN (1750 6575);
DISPLAY INVISIBLE (1750 6575);
FORCEPROP 1 LAST COMMENT_BODY TRUE
J 0
(1400 6600);
DISPLAY 0.872340 (1400 6600);
PAINT GREEN (1400 6600);
DISPLAY INVISIBLE (1400 6600);
FORCEPROP 2 LAST PATH I147
J 0
(1625 6750);
DISPLAY 0.680851 (1625 6750);
DISPLAY INVISIBLE (1625 6750);
FORCEADD OFFPAGE..4
(1425 6800);
FORCEPROP 2 LAST $XR0 132 
J 0
(1611 6800);
DISPLAY 0.638298 (1611 6800);
PAINT MONO (1611 6800);
FORCEPROP 2 LAST CDS_LIB standard
J 0
(1425 6800);
PAINT MONO (1425 6800);
DISPLAY INVISIBLE (1425 6800);
FORCEPROP 1 LAST OFFPAGE TRUE
J 0
(1750 6675);
DISPLAY 0.872340 (1750 6675);
PAINT GREEN (1750 6675);
DISPLAY INVISIBLE (1750 6675);
FORCEPROP 1 LAST COMMENT_BODY TRUE
J 0
(1400 6700);
DISPLAY 0.872340 (1400 6700);
PAINT GREEN (1400 6700);
DISPLAY INVISIBLE (1400 6700);
FORCEPROP 2 LAST PATH I148
J 0
(1625 6850);
DISPLAY 0.680851 (1625 6850);
DISPLAY INVISIBLE (1625 6850);
FORCEADD OFFPAGE..4
(1425 6850);
FORCEPROP 2 LAST $XR0 131 
J 0
(1611 6850);
DISPLAY 0.638298 (1611 6850);
PAINT MONO (1611 6850);
FORCEPROP 2 LAST CDS_LIB standard
J 0
(1425 6850);
PAINT MONO (1425 6850);
DISPLAY INVISIBLE (1425 6850);
FORCEPROP 1 LAST OFFPAGE TRUE
J 0
(1750 6725);
DISPLAY 0.872340 (1750 6725);
PAINT GREEN (1750 6725);
DISPLAY INVISIBLE (1750 6725);
FORCEPROP 1 LAST COMMENT_BODY TRUE
J 0
(1400 6750);
DISPLAY 0.872340 (1400 6750);
PAINT GREEN (1400 6750);
DISPLAY INVISIBLE (1400 6750);
FORCEPROP 2 LAST PATH I149
J 0
(1625 6900);
DISPLAY 0.680851 (1625 6900);
DISPLAY INVISIBLE (1625 6900);
FORCEADD OFFPAGE..5
(-2000 1800);
FORCEPROP 2 LAST $XR1 131 
J 0
(-2374 1800);
DISPLAY 0.638298 (-2374 1800);
PAINT MONO (-2374 1800);
FORCEPROP 2 LAST $XR0 80 
J 0
(-2254 1800);
DISPLAY 0.638298 (-2254 1800);
PAINT MONO (-2254 1800);
FORCEPROP 2 LAST CDS_LIB standard
J 0
(-2000 1800);
PAINT MONO (-2000 1800);
DISPLAY INVISIBLE (-2000 1800);
FORCEPROP 1 LAST OFFPAGE TRUE
J 0
(-1675 1675);
DISPLAY 0.872340 (-1675 1675);
PAINT GREEN (-1675 1675);
DISPLAY INVISIBLE (-1675 1675);
FORCEPROP 1 LAST COMMENT_BODY TRUE
J 0
(-1900 1725);
DISPLAY 0.872340 (-1900 1725);
PAINT GREEN (-1900 1725);
DISPLAY INVISIBLE (-1900 1725);
FORCEPROP 2 LAST PATH I15
J 0
(-2275 1850);
DISPLAY 0.680851 (-2275 1850);
DISPLAY INVISIBLE (-2275 1850);
FORCEADD OFFPAGE..4
(1425 6900);
FORCEPROP 2 LAST $XR0 132 
J 0
(1611 6900);
DISPLAY 0.638298 (1611 6900);
PAINT MONO (1611 6900);
FORCEPROP 2 LAST CDS_LIB standard
J 0
(1425 6900);
DISPLAY INVISIBLE (1425 6900);
FORCEPROP 1 LAST OFFPAGE TRUE
J 0
(1750 6775);
DISPLAY 0.872340 (1750 6775);
PAINT GREEN (1750 6775);
DISPLAY INVISIBLE (1750 6775);
FORCEPROP 1 LAST COMMENT_BODY TRUE
J 0
(1400 6800);
DISPLAY 0.872340 (1400 6800);
PAINT GREEN (1400 6800);
DISPLAY INVISIBLE (1400 6800);
FORCEPROP 2 LAST PATH I150
J 0
(1625 6950);
DISPLAY 0.680851 (1625 6950);
DISPLAY INVISIBLE (1625 6950);
FORCEADD OFFPAGE..2
(1425 6950);
FORCEPROP 2 LAST $XR0 132 
J 0
(1614 6950);
DISPLAY 0.638298 (1614 6950);
PAINT MONO (1614 6950);
FORCEPROP 2 LAST CDS_LIB standard
J 0
(1425 6950);
DISPLAY INVISIBLE (1425 6950);
FORCEPROP 1 LAST OFFPAGE TRUE
J 0
(1750 6825);
DISPLAY 0.872340 (1750 6825);
PAINT GREEN (1750 6825);
DISPLAY INVISIBLE (1750 6825);
FORCEPROP 1 LAST COMMENT_BODY TRUE
J 0
(1380 6855);
DISPLAY 0.872340 (1380 6855);
PAINT GREEN (1380 6855);
DISPLAY INVISIBLE (1380 6855);
FORCEPROP 2 LAST PATH I151
J 0
(1625 7000);
DISPLAY 0.680851 (1625 7000);
DISPLAY INVISIBLE (1625 7000);
FORCEADD OFFPAGE..2
(1425 7000);
FORCEPROP 2 LAST $XR0 133 
J 0
(1614 7000);
DISPLAY 0.638298 (1614 7000);
PAINT MONO (1614 7000);
FORCEPROP 2 LAST CDS_LIB standard
J 0
(1425 7000);
PAINT MONO (1425 7000);
DISPLAY INVISIBLE (1425 7000);
FORCEPROP 1 LAST OFFPAGE TRUE
J 0
(1750 6875);
DISPLAY 0.872340 (1750 6875);
PAINT GREEN (1750 6875);
DISPLAY INVISIBLE (1750 6875);
FORCEPROP 1 LAST COMMENT_BODY TRUE
J 0
(1380 6905);
DISPLAY 0.872340 (1380 6905);
PAINT GREEN (1380 6905);
DISPLAY INVISIBLE (1380 6905);
FORCEPROP 2 LAST PATH I152
J 0
(1625 7050);
DISPLAY 0.680851 (1625 7050);
DISPLAY INVISIBLE (1625 7050);
FORCEADD OFFPAGE..4
(1425 7100);
FORCEPROP 2 LAST $XR0 133 
J 0
(1611 7100);
DISPLAY 0.638298 (1611 7100);
PAINT MONO (1611 7100);
FORCEPROP 2 LAST CDS_LIB standard
J 0
(1425 7100);
PAINT MONO (1425 7100);
DISPLAY INVISIBLE (1425 7100);
FORCEPROP 1 LAST OFFPAGE TRUE
J 0
(1750 6975);
DISPLAY 0.872340 (1750 6975);
PAINT GREEN (1750 6975);
DISPLAY INVISIBLE (1750 6975);
FORCEPROP 1 LAST COMMENT_BODY TRUE
J 0
(1400 7000);
DISPLAY 0.872340 (1400 7000);
PAINT GREEN (1400 7000);
DISPLAY INVISIBLE (1400 7000);
FORCEPROP 2 LAST PATH I153
J 0
(1625 7150);
DISPLAY 0.680851 (1625 7150);
DISPLAY INVISIBLE (1625 7150);
FORCEADD OFFPAGE..4
(1425 7050);
FORCEPROP 2 LAST $XR0 133 
J 0
(1611 7050);
DISPLAY 0.638298 (1611 7050);
PAINT MONO (1611 7050);
FORCEPROP 2 LAST CDS_LIB standard
J 0
(1425 7050);
PAINT MONO (1425 7050);
DISPLAY INVISIBLE (1425 7050);
FORCEPROP 1 LAST OFFPAGE TRUE
J 0
(1750 6925);
DISPLAY 0.872340 (1750 6925);
PAINT GREEN (1750 6925);
DISPLAY INVISIBLE (1750 6925);
FORCEPROP 1 LAST COMMENT_BODY TRUE
J 0
(1400 6950);
DISPLAY 0.872340 (1400 6950);
PAINT GREEN (1400 6950);
DISPLAY INVISIBLE (1400 6950);
FORCEPROP 2 LAST PATH I154
J 0
(1625 7100);
DISPLAY 0.680851 (1625 7100);
DISPLAY INVISIBLE (1625 7100);
FORCEADD UNIVERSAL_GND..1
(3125 5325);
FORCEPROP 3 LASTPIN (3125 5375) SIG_NAME GND\g
J 0
(3135 5385);
DISPLAY 0.659574 (3135 5385);
PAINT MONO (3135 5385);
DISPLAY INVISIBLE (3135 5385);
FORCEPROP 2 LAST ROOM IO_SLOT
J 1
(2900 5400);
DISPLAY 0.744681 (2900 5400);
FORCEPROP 2 LAST CDS_LIB pure_quanta_power
J 0
(3125 5325);
DISPLAY INVISIBLE (3125 5325);
FORCEPROP 1 LAST HDL_POWER GND
J 1
(3150 5250);
DISPLAY 0.872340 (3150 5250);
PAINT GREEN (3150 5250);
DISPLAY INVISIBLE (3150 5250);
FORCEPROP 1 LAST PATH I155
J 0
(3200 5325);
DISPLAY 0.872340 (3200 5325);
PAINT AQUA (3200 5325);
DISPLAY INVISIBLE (3200 5325);
FORCEADD OFFPAGE..4
(3275 5900);
FORCEPROP 2 LAST $XR0 132 
J 0
(3461 5900);
DISPLAY 0.638298 (3461 5900);
PAINT MONO (3461 5900);
FORCEPROP 2 LAST CDS_LIB standard
J 0
(3275 5900);
DISPLAY INVISIBLE (3275 5900);
FORCEPROP 1 LAST OFFPAGE TRUE
J 0
(3600 5775);
DISPLAY 0.872340 (3600 5775);
PAINT GREEN (3600 5775);
DISPLAY INVISIBLE (3600 5775);
FORCEPROP 1 LAST COMMENT_BODY TRUE
J 0
(3250 5800);
DISPLAY 0.872340 (3250 5800);
PAINT GREEN (3250 5800);
DISPLAY INVISIBLE (3250 5800);
FORCEPROP 2 LAST PATH I157
J 0
(3500 5950);
DISPLAY 0.680851 (3500 5950);
DISPLAY INVISIBLE (3500 5950);
FORCEADD OFFPAGE..4
(3275 6000);
FORCEPROP 2 LAST $XR0 248 
J 0
(3461 6000);
DISPLAY 0.638298 (3461 6000);
PAINT MONO (3461 6000);
FORCEPROP 2 LAST CDS_LIB standard
J 0
(3275 6000);
PAINT MONO (3275 6000);
DISPLAY INVISIBLE (3275 6000);
FORCEPROP 1 LAST OFFPAGE TRUE
J 0
(3600 5875);
DISPLAY 0.872340 (3600 5875);
PAINT GREEN (3600 5875);
DISPLAY INVISIBLE (3600 5875);
FORCEPROP 1 LAST COMMENT_BODY TRUE
J 0
(3250 5900);
DISPLAY 0.872340 (3250 5900);
PAINT GREEN (3250 5900);
DISPLAY INVISIBLE (3250 5900);
FORCEPROP 2 LAST PATH I158
J 0
(3475 6050);
DISPLAY 0.680851 (3475 6050);
DISPLAY INVISIBLE (3475 6050);
FORCEADD OFFPAGE..3
(3275 5950);
FORCEPROP 2 LAST $XR0 248 
J 0
(3489 5950);
DISPLAY 0.638298 (3489 5950);
PAINT MONO (3489 5950);
FORCEPROP 2 LAST CDS_LIB standard
J 0
(3275 5950);
PAINT MONO (3275 5950);
DISPLAY INVISIBLE (3275 5950);
FORCEPROP 1 LAST OFFPAGE TRUE
J 0
(3600 5825);
DISPLAY 0.872340 (3600 5825);
DISPLAY INVISIBLE (3600 5825);
FORCEPROP 1 LAST COMMENT_BODY TRUE
J 0
(3225 5850);
DISPLAY 0.872340 (3225 5850);
PAINT GREEN (3225 5850);
DISPLAY INVISIBLE (3225 5850);
FORCEPROP 2 LAST PATH I159
J 0
(3500 6000);
DISPLAY 0.680851 (3500 6000);
DISPLAY INVISIBLE (3500 6000);
FORCEADD OFFPAGE..5
(-2000 1975);
FORCEPROP 2 LAST $XR1 131 
J 0
(-2374 1975);
DISPLAY 0.638298 (-2374 1975);
PAINT MONO (-2374 1975);
FORCEPROP 2 LAST $XR0 80 
J 0
(-2254 1975);
DISPLAY 0.638298 (-2254 1975);
PAINT MONO (-2254 1975);
FORCEPROP 2 LAST CDS_LIB standard
J 0
(-2000 1975);
PAINT MONO (-2000 1975);
DISPLAY INVISIBLE (-2000 1975);
FORCEPROP 1 LAST OFFPAGE TRUE
J 0
(-1675 1850);
DISPLAY 0.872340 (-1675 1850);
PAINT GREEN (-1675 1850);
DISPLAY INVISIBLE (-1675 1850);
FORCEPROP 1 LAST COMMENT_BODY TRUE
J 0
(-1900 1900);
DISPLAY 0.872340 (-1900 1900);
PAINT GREEN (-1900 1900);
DISPLAY INVISIBLE (-1900 1900);
FORCEPROP 2 LAST PATH I16
J 0
(-2275 2025);
DISPLAY 0.680851 (-2275 2025);
DISPLAY INVISIBLE (-2275 2025);
FORCEADD OFFPAGE..2
(-3225 1950);
FORCEPROP 2 LAST $XR0 131 
J 0
(-3036 1950);
DISPLAY 0.638298 (-3036 1950);
PAINT MONO (-3036 1950);
FORCEPROP 2 LAST CDS_LIB standard
J 0
(-3225 1950);
PAINT MONO (-3225 1950);
DISPLAY INVISIBLE (-3225 1950);
FORCEPROP 1 LAST OFFPAGE TRUE
J 0
(-2900 1825);
DISPLAY 0.872340 (-2900 1825);
PAINT GREEN (-2900 1825);
DISPLAY INVISIBLE (-2900 1825);
FORCEPROP 1 LAST COMMENT_BODY TRUE
J 0
(-3270 1855);
DISPLAY 0.872340 (-3270 1855);
PAINT GREEN (-3270 1855);
DISPLAY INVISIBLE (-3270 1855);
FORCEPROP 2 LAST PATH I160
J 0
(-3025 2000);
DISPLAY 0.680851 (-3025 2000);
DISPLAY INVISIBLE (-3025 2000);
FORCEADD OFFPAGE..2
(-3225 2000);
FORCEPROP 2 LAST $XR0 131 
J 0
(-3036 2000);
DISPLAY 0.638298 (-3036 2000);
PAINT MONO (-3036 2000);
FORCEPROP 2 LAST CDS_LIB standard
J 0
(-3225 2000);
PAINT MONO (-3225 2000);
DISPLAY INVISIBLE (-3225 2000);
FORCEPROP 1 LAST OFFPAGE TRUE
J 0
(-2900 1875);
DISPLAY 0.872340 (-2900 1875);
PAINT GREEN (-2900 1875);
DISPLAY INVISIBLE (-2900 1875);
FORCEPROP 1 LAST COMMENT_BODY TRUE
J 0
(-3270 1905);
DISPLAY 0.872340 (-3270 1905);
PAINT GREEN (-3270 1905);
DISPLAY INVISIBLE (-3270 1905);
FORCEPROP 2 LAST PATH I161
J 0
(-3025 2050);
DISPLAY 0.680851 (-3025 2050);
DISPLAY INVISIBLE (-3025 2050);
FORCEADD TAP..1
(775 2850);
FORCEPROP 3 LASTPIN (725 2850) SIG_NAME P5E_CPU0_G3_RX_DP<15>
J 0
(735 2860);
DISPLAY 0.659574 (735 2860);
PAINT MONO (735 2860);
DISPLAY INVISIBLE (735 2860);
FORCEPROP 1 LASTPIN (725 2850) BN 15
J 0
(713 2858);
DISPLAY 0.680851 (713 2858);
PAINT GREEN (713 2858);
FORCEPROP 2 LAST CDS_LIB standard
J 0
(775 2850);
PAINT MONO (775 2850);
DISPLAY INVISIBLE (775 2850);
FORCEPROP 1 LAST BODY_TYPE PLUMBING
J 0
(775 2900);
DISPLAY 0.872340 (775 2900);
PAINT GREEN (775 2900);
DISPLAY INVISIBLE (775 2900);
FORCEPROP 1 LAST HDL_TAP TRUE
J 0
(1100 2725);
DISPLAY 0.872340 (1100 2725);
PAINT GREEN (1100 2725);
DISPLAY INVISIBLE (1100 2725);
FORCEPROP 1 LAST PATH I162
J 0
(773 2850);
DISPLAY 0.872340 (773 2850);
PAINT GREEN (773 2850);
DISPLAY INVISIBLE (773 2850);
FORCEADD Q_CAP..1
(1775 1750);
FORCEPROP 1 LAST LOCATION C27
J 0
(1825 1850);
DISPLAY 0.787234 (1825 1850);
FORCEPROP 2 LAST $SEC 1
J 0
(1825 1950);
DISPLAY 0.680851 (1825 1950);
PAINT MONO (1825 1950);
DISPLAY INVISIBLE (1825 1950);
FORCEPROP 2 LAST CDS_SEC 1
J 0
(1825 1950);
DISPLAY 1.021277 (1825 1950);
DISPLAY INVISIBLE (1825 1950);
FORCEPROP 1 LASTPIN (1775 1850) $PN 1
J 0
(1785 1830);
DISPLAY 0.787234 (1785 1830);
FORCEPROP 1 LASTPIN (1775 1650) $PN 2
J 0
(1785 1630);
DISPLAY 0.787234 (1785 1630);
FORCEPROP 1 LAST TOLERANCE 10%
J 0
(1825 1700);
DISPLAY 0.638298 (1825 1700);
FORCEPROP 1 LAST VALUE 0.1UF
J 0
(1825 1800);
DISPLAY 0.638298 (1825 1800);
FORCEPROP 1 LAST VOLTAGE 25V
J 0
(1825 1750);
DISPLAY 0.638298 (1825 1750);
FORCEPROP 1 LAST PACK_TYPE 0402
J 0
(1825 1600);
DISPLAY 0.638298 (1825 1600);
FORCEPROP 1 LAST MATERIAL X7R
J 0
(1825 1650);
DISPLAY 0.638298 (1825 1650);
FORCEPROP 2 LAST CDS_LIB pure_quanta
J 0
(1775 1750);
PAINT MONO (1775 1750);
DISPLAY INVISIBLE (1775 1750);
FORCEPROP 1 LAST PATH I163
J 0
(1825 1900);
DISPLAY 0.978723 (1825 1900);
PAINT WHITE (1825 1900);
DISPLAY INVISIBLE (1825 1900);
FORCEPROP 1 LAST PART_NUMBER CH4104K1B00
J 0
(1825 1600);
DISPLAY 0.808511 (1825 1600);
DISPLAY INVISIBLE (1825 1600);
FORCEADD Q_CAP..1
(2325 1750);
FORCEPROP 1 LAST LOCATION C1236
J 0
(2375 1850);
DISPLAY 0.787234 (2375 1850);
FORCEPROP 2 LAST $SEC 1
J 0
(2375 1950);
DISPLAY 0.680851 (2375 1950);
PAINT MONO (2375 1950);
DISPLAY INVISIBLE (2375 1950);
FORCEPROP 2 LAST CDS_SEC 1
J 0
(2375 1950);
DISPLAY 1.021277 (2375 1950);
DISPLAY INVISIBLE (2375 1950);
FORCEPROP 1 LASTPIN (2325 1850) $PN 1
J 0
(2335 1830);
DISPLAY 0.787234 (2335 1830);
FORCEPROP 1 LASTPIN (2325 1650) $PN 2
J 0
(2335 1630);
DISPLAY 0.787234 (2335 1630);
FORCEPROP 1 LAST PACK_TYPE 0402
J 0
(2375 1600);
DISPLAY 0.638298 (2375 1600);
FORCEPROP 1 LAST VOLTAGE 25V
J 0
(2375 1750);
DISPLAY 0.638298 (2375 1750);
FORCEPROP 1 LAST TOLERANCE 10%
J 0
(2375 1700);
DISPLAY 0.638298 (2375 1700);
FORCEPROP 1 LAST VALUE 0.1UF
J 0
(2375 1800);
DISPLAY 0.638298 (2375 1800);
FORCEPROP 1 LAST MATERIAL X7R
J 0
(2375 1650);
DISPLAY 0.638298 (2375 1650);
FORCEPROP 2 LAST CDS_LIB pure_quanta
J 0
(2325 1750);
PAINT MONO (2325 1750);
DISPLAY INVISIBLE (2325 1750);
FORCEPROP 1 LAST PATH I164
J 0
(2375 1900);
DISPLAY 0.978723 (2375 1900);
PAINT WHITE (2375 1900);
DISPLAY INVISIBLE (2375 1900);
FORCEPROP 1 LAST PART_NUMBER CH4104K1B00
J 0
(2375 1550);
DISPLAY 0.638298 (2375 1550);
DISPLAY INVISIBLE (2375 1550);
FORCEADD OFFPAGE..4
(1175 2650);
FORCEPROP 2 LAST $XR0 133 
J 0
(1361 2650);
DISPLAY 0.638298 (1361 2650);
PAINT MONO (1361 2650);
FORCEPROP 2 LAST CDS_LIB standard
J 0
(1175 2650);
PAINT MONO (1175 2650);
DISPLAY INVISIBLE (1175 2650);
FORCEPROP 1 LAST OFFPAGE TRUE
J 0
(1500 2525);
DISPLAY 0.872340 (1500 2525);
PAINT GREEN (1500 2525);
DISPLAY INVISIBLE (1500 2525);
FORCEPROP 1 LAST COMMENT_BODY TRUE
J 0
(1150 2550);
DISPLAY 0.872340 (1150 2550);
PAINT GREEN (1150 2550);
DISPLAY INVISIBLE (1150 2550);
FORCEPROP 2 LAST PATH I165
J 0
(1375 2700);
DISPLAY 0.680851 (1375 2700);
DISPLAY INVISIBLE (1375 2700);
FORCEADD Q_RES..1
(1525 2750);
FORCEPROP 1 LAST LOCATION R42
J 0
(1250 2750);
DISPLAY 0.638298 (1250 2750);
FORCEPROP 2 LAST $SEC 1
J 0
(1475 2950);
DISPLAY 0.680851 (1475 2950);
PAINT MONO (1475 2950);
DISPLAY INVISIBLE (1475 2950);
FORCEPROP 2 LAST CDS_SEC 1
J 0
(1475 2950);
DISPLAY 1.021277 (1475 2950);
DISPLAY INVISIBLE (1475 2950);
FORCEPROP 1 LASTPIN (1425 2750) $PN 1
J 0
(1437 2762);
DISPLAY 0.787234 (1437 2762);
FORCEPROP 1 LASTPIN (1625 2750) $PN 2
J 0
(1587 2762);
DISPLAY 0.787234 (1587 2762);
FORCEPROP 1 LAST PACK_TYPE 0402LF
J 0
(1800 2750);
DISPLAY 0.638298 (1800 2750);
FORCEPROP 1 LAST MATERIAL CHIP
J 0
(1450 2850);
DISPLAY 0.638298 (1450 2850);
FORCEPROP 1 LAST WATTAGE 1/16W
J 2
(1725 2850);
DISPLAY 0.638298 (1725 2850);
FORCEPROP 1 LAST VALUE 0
J 2
(1700 2750);
DISPLAY 0.638298 (1700 2750);
FORCEPROP 1 LAST TOLERANCE 5%
J 0
(1725 2750);
DISPLAY 0.638298 (1725 2750);
FORCEPROP 2 LAST CDS_LIB pure_quanta
J 0
(1525 2750);
PAINT MONO (1525 2750);
DISPLAY INVISIBLE (1525 2750);
FORCEPROP 1 LAST PATH I166
J 0
(1475 2900);
DISPLAY 0.978723 (1475 2900);
PAINT WHITE (1475 2900);
DISPLAY INVISIBLE (1475 2900);
FORCEPROP 1 LAST PART_NUMBER CS00002JB13
J 0
(1425 2800);
DISPLAY 0.638298 (1425 2800);
DISPLAY INVISIBLE (1425 2800);
FORCEADD TAP..1
R 2
(-1575 3350);
FORCEPROP 3 LASTPIN (-1525 3350) SIG_NAME P5E_CPU0_G3_TX_C_DP<12>
J 0
(-1515 3360);
DISPLAY 0.659574 (-1515 3360);
PAINT MONO (-1515 3360);
DISPLAY INVISIBLE (-1515 3360);
FORCEPROP 1 LASTPIN (-1525 3350) BN 12
J 2
(-1513 3358);
DISPLAY 0.680851 (-1513 3358);
PAINT GREEN (-1513 3358);
FORCEPROP 2 LAST CDS_LIB standard
J 0
(-1575 3350);
PAINT MONO (-1575 3350);
DISPLAY INVISIBLE (-1575 3350);
FORCEPROP 1 LAST BODY_TYPE PLUMBING
J 2
(-1575 3400);
DISPLAY 0.872340 (-1575 3400);
PAINT GREEN (-1575 3400);
DISPLAY INVISIBLE (-1575 3400);
FORCEPROP 1 LAST HDL_TAP TRUE
J 2
(-1900 3225);
DISPLAY 0.872340 (-1900 3225);
PAINT GREEN (-1900 3225);
DISPLAY INVISIBLE (-1900 3225);
FORCEPROP 1 LAST PATH I167
J 2
(-1573 3350);
DISPLAY 0.872340 (-1573 3350);
PAINT GREEN (-1573 3350);
DISPLAY INVISIBLE (-1573 3350);
FORCEADD SCONN168_ME1016810202011..1
(-350 4725);
FORCEPROP 1 LAST LOCATION J38
J 0
(-839 7492);
DISPLAY 0.723404 (-839 7492);
PAINT GREEN (-839 7492);
FORCEPROP 2 LAST SEC 1
J 0
(-825 7650);
DISPLAY 0.680851 (-825 7650);
PAINT MONO (-825 7650);
DISPLAY INVISIBLE (-825 7650);
FORCEPROP 2 LASTPIN (-1000 5800) $PN B11
J 2
(-1010 5810);
DISPLAY 0.680851 (-1010 5810);
PAINT MONO (-1010 5810);
FORCEPROP 2 LASTPIN (-1000 6300) $PN B1
J 2
(-1010 6310);
DISPLAY 0.680851 (-1010 6310);
PAINT MONO (-1010 6310);
FORCEPROP 2 LASTPIN (-1000 6250) $PN B2
J 2
(-1010 6260);
DISPLAY 0.680851 (-1010 6260);
PAINT MONO (-1010 6260);
FORCEPROP 2 LASTPIN (-1000 6200) $PN B3
J 2
(-1010 6210);
DISPLAY 0.680851 (-1010 6210);
PAINT MONO (-1010 6210);
FORCEPROP 2 LASTPIN (-1000 6150) $PN B4
J 2
(-1010 6160);
DISPLAY 0.680851 (-1010 6160);
PAINT MONO (-1010 6160);
FORCEPROP 2 LASTPIN (-1000 6100) $PN B5
J 2
(-1010 6110);
DISPLAY 0.680851 (-1010 6110);
PAINT MONO (-1010 6110);
FORCEPROP 2 LASTPIN (-1000 6050) $PN B6
J 2
(-1010 6060);
DISPLAY 0.680851 (-1010 6060);
PAINT MONO (-1010 6060);
FORCEPROP 2 LASTPIN (-1000 5750) $PN B12
J 2
(-1010 5760);
DISPLAY 0.680851 (-1010 5760);
PAINT MONO (-1010 5760);
FORCEPROP 2 LASTPIN (-1000 6000) $PN B7
J 2
(-1010 6010);
DISPLAY 0.680851 (-1010 6010);
PAINT MONO (-1010 6010);
FORCEPROP 2 LASTPIN (-1000 5950) $PN B8
J 2
(-1010 5960);
DISPLAY 0.680851 (-1010 5960);
PAINT MONO (-1010 5960);
FORCEPROP 2 LASTPIN (-1000 5900) $PN B9
J 2
(-1010 5910);
DISPLAY 0.680851 (-1010 5910);
PAINT MONO (-1010 5910);
FORCEPROP 2 LASTPIN (-1000 6850) $PN OB6
J 2
(-1010 6860);
DISPLAY 0.680851 (-1010 6860);
PAINT MONO (-1010 6860);
FORCEPROP 2 LASTPIN (-1000 6950) $PN OB4
J 2
(-1010 6960);
DISPLAY 0.680851 (-1010 6960);
PAINT MONO (-1010 6960);
FORCEPROP 2 LASTPIN (-1000 6900) $PN OB5
J 2
(-1010 6910);
DISPLAY 0.680851 (-1010 6910);
PAINT MONO (-1010 6910);
FORCEPROP 2 LASTPIN (300 2550) $PN G1
J 0
(310 2560);
DISPLAY 0.680851 (310 2560);
PAINT MONO (310 2560);
FORCEPROP 2 LASTPIN (300 2500) $PN G2
J 0
(310 2510);
DISPLAY 0.680851 (310 2510);
PAINT MONO (310 2510);
FORCEPROP 2 LASTPIN (300 2450) $PN G3
J 0
(310 2460);
DISPLAY 0.680851 (310 2460);
PAINT MONO (310 2460);
FORCEPROP 2 LASTPIN (300 2400) $PN G4
J 0
(310 2410);
DISPLAY 0.680851 (310 2410);
PAINT MONO (310 2410);
FORCEPROP 2 LASTPIN (300 2350) $PN G5
J 0
(310 2360);
DISPLAY 0.680851 (310 2360);
PAINT MONO (310 2360);
FORCEPROP 2 LASTPIN (300 6300) $PN A1
J 0
(310 6310);
DISPLAY 0.680851 (310 6310);
PAINT MONO (310 6310);
FORCEPROP 2 LASTPIN (300 6250) $PN A2
J 0
(310 6260);
DISPLAY 0.680851 (310 6260);
PAINT MONO (310 6260);
FORCEPROP 2 LASTPIN (300 6200) $PN A3
J 0
(310 6210);
DISPLAY 0.680851 (310 6210);
PAINT MONO (310 6210);
FORCEPROP 2 LASTPIN (300 6150) $PN A4
J 0
(310 6160);
DISPLAY 0.680851 (310 6160);
PAINT MONO (310 6160);
FORCEPROP 2 LASTPIN (300 6100) $PN A5
J 0
(310 6110);
DISPLAY 0.680851 (310 6110);
PAINT MONO (310 6110);
FORCEPROP 2 LASTPIN (300 6050) $PN A6
J 0
(310 6060);
DISPLAY 0.680851 (310 6060);
PAINT MONO (310 6060);
FORCEPROP 2 LASTPIN (300 5700) $PN A13
J 0
(310 5710);
DISPLAY 0.680851 (310 5710);
PAINT MONO (310 5710);
FORCEPROP 2 LASTPIN (300 5550) $PN A16
J 0
(310 5560);
DISPLAY 0.680851 (310 5560);
PAINT MONO (310 5560);
FORCEPROP 2 LASTPIN (300 5400) $PN A19
J 0
(310 5410);
DISPLAY 0.680851 (310 5410);
PAINT MONO (310 5410);
FORCEPROP 2 LASTPIN (300 5250) $PN A22
J 0
(310 5260);
DISPLAY 0.680851 (310 5260);
PAINT MONO (310 5260);
FORCEPROP 2 LASTPIN (300 5100) $PN A25
J 0
(310 5110);
DISPLAY 0.680851 (310 5110);
PAINT MONO (310 5110);
FORCEPROP 2 LASTPIN (300 4950) $PN A28
J 0
(310 4960);
DISPLAY 0.680851 (310 4960);
PAINT MONO (310 4960);
FORCEPROP 2 LASTPIN (300 4800) $PN A29
J 0
(310 4810);
DISPLAY 0.680851 (310 4810);
PAINT MONO (310 4810);
FORCEPROP 2 LASTPIN (300 4650) $PN A32
J 0
(310 4660);
DISPLAY 0.680851 (310 4660);
PAINT MONO (310 4660);
FORCEPROP 2 LASTPIN (300 4500) $PN A35
J 0
(310 4510);
DISPLAY 0.680851 (310 4510);
PAINT MONO (310 4510);
FORCEPROP 2 LASTPIN (300 4350) $PN A38
J 0
(310 4360);
DISPLAY 0.680851 (310 4360);
PAINT MONO (310 4360);
FORCEPROP 2 LASTPIN (300 4200) $PN A41
J 0
(310 4210);
DISPLAY 0.680851 (310 4210);
PAINT MONO (310 4210);
FORCEPROP 2 LASTPIN (300 4000) $PN A43
J 0
(310 4010);
DISPLAY 0.680851 (310 4010);
PAINT MONO (310 4010);
FORCEPROP 2 LASTPIN (300 3850) $PN A46
J 0
(310 3860);
DISPLAY 0.680851 (310 3860);
PAINT MONO (310 3860);
FORCEPROP 2 LASTPIN (300 3700) $PN A49
J 0
(310 3710);
DISPLAY 0.680851 (310 3710);
PAINT MONO (310 3710);
FORCEPROP 2 LASTPIN (300 3550) $PN A52
J 0
(310 3560);
DISPLAY 0.680851 (310 3560);
PAINT MONO (310 3560);
FORCEPROP 2 LASTPIN (300 3400) $PN A55
J 0
(310 3410);
DISPLAY 0.680851 (310 3410);
PAINT MONO (310 3410);
FORCEPROP 2 LASTPIN (300 3250) $PN A58
J 0
(310 3260);
DISPLAY 0.680851 (310 3260);
PAINT MONO (310 3260);
FORCEPROP 2 LASTPIN (300 3100) $PN A61
J 0
(310 3110);
DISPLAY 0.680851 (310 3110);
PAINT MONO (310 3110);
FORCEPROP 2 LASTPIN (300 2950) $PN A64
J 0
(310 2960);
DISPLAY 0.680851 (310 2960);
PAINT MONO (310 2960);
FORCEPROP 2 LASTPIN (300 2800) $PN A67
J 0
(310 2810);
DISPLAY 0.680851 (310 2810);
PAINT MONO (310 2810);
FORCEPROP 2 LASTPIN (-1000 5700) $PN B13
J 2
(-1010 5710);
DISPLAY 0.680851 (-1010 5710);
PAINT MONO (-1010 5710);
FORCEPROP 2 LASTPIN (-1000 5550) $PN B16
J 2
(-1010 5560);
DISPLAY 0.680851 (-1010 5560);
PAINT MONO (-1010 5560);
FORCEPROP 2 LASTPIN (-1000 5400) $PN B19
J 2
(-1010 5410);
DISPLAY 0.680851 (-1010 5410);
PAINT MONO (-1010 5410);
FORCEPROP 2 LASTPIN (-1000 5250) $PN B22
J 2
(-1010 5260);
DISPLAY 0.680851 (-1010 5260);
PAINT MONO (-1010 5260);
FORCEPROP 2 LASTPIN (-1000 5100) $PN B25
J 2
(-1010 5110);
DISPLAY 0.680851 (-1010 5110);
PAINT MONO (-1010 5110);
FORCEPROP 2 LASTPIN (-1000 4950) $PN B28
J 2
(-1010 4960);
DISPLAY 0.680851 (-1010 4960);
PAINT MONO (-1010 4960);
FORCEPROP 2 LASTPIN (-1000 4800) $PN B29
J 2
(-1010 4810);
DISPLAY 0.680851 (-1010 4810);
PAINT MONO (-1010 4810);
FORCEPROP 2 LASTPIN (-1000 4650) $PN B32
J 2
(-1010 4660);
DISPLAY 0.680851 (-1010 4660);
PAINT MONO (-1010 4660);
FORCEPROP 2 LASTPIN (-1000 4500) $PN B35
J 2
(-1010 4510);
DISPLAY 0.680851 (-1010 4510);
PAINT MONO (-1010 4510);
FORCEPROP 2 LASTPIN (-1000 4350) $PN B38
J 2
(-1010 4360);
DISPLAY 0.680851 (-1010 4360);
PAINT MONO (-1010 4360);
FORCEPROP 2 LASTPIN (-1000 4200) $PN B41
J 2
(-1010 4210);
DISPLAY 0.680851 (-1010 4210);
PAINT MONO (-1010 4210);
FORCEPROP 2 LASTPIN (-1000 4000) $PN B43
J 2
(-1010 4010);
DISPLAY 0.680851 (-1010 4010);
PAINT MONO (-1010 4010);
FORCEPROP 2 LASTPIN (-1000 3850) $PN B46
J 2
(-1010 3860);
DISPLAY 0.680851 (-1010 3860);
PAINT MONO (-1010 3860);
FORCEPROP 2 LASTPIN (-1000 3700) $PN B49
J 2
(-1010 3710);
DISPLAY 0.680851 (-1010 3710);
PAINT MONO (-1010 3710);
FORCEPROP 2 LASTPIN (-1000 3550) $PN B52
J 2
(-1010 3560);
DISPLAY 0.680851 (-1010 3560);
PAINT MONO (-1010 3560);
FORCEPROP 2 LASTPIN (-1000 3400) $PN B55
J 2
(-1010 3410);
DISPLAY 0.680851 (-1010 3410);
PAINT MONO (-1010 3410);
FORCEPROP 2 LASTPIN (-1000 3250) $PN B58
J 2
(-1010 3260);
DISPLAY 0.680851 (-1010 3260);
PAINT MONO (-1010 3260);
FORCEPROP 2 LASTPIN (-1000 3100) $PN B61
J 2
(-1010 3110);
DISPLAY 0.680851 (-1010 3110);
PAINT MONO (-1010 3110);
FORCEPROP 2 LASTPIN (-1000 2950) $PN B64
J 2
(-1010 2960);
DISPLAY 0.680851 (-1010 2960);
PAINT MONO (-1010 2960);
FORCEPROP 2 LASTPIN (-1000 2800) $PN B67
J 2
(-1010 2810);
DISPLAY 0.680851 (-1010 2810);
PAINT MONO (-1010 2810);
FORCEPROP 2 LASTPIN (300 6650) $PN OA10
J 0
(310 6660);
DISPLAY 0.680851 (310 6660);
PAINT MONO (310 6660);
FORCEPROP 2 LASTPIN (300 6500) $PN OA13
J 0
(310 6510);
DISPLAY 0.680851 (310 6510);
PAINT MONO (310 6510);
FORCEPROP 2 LASTPIN (-1000 6650) $PN OB10
J 2
(-1010 6660);
DISPLAY 0.680851 (-1010 6660);
PAINT MONO (-1010 6660);
FORCEPROP 2 LASTPIN (-1000 6500) $PN OB13
J 2
(-1010 6510);
DISPLAY 0.680851 (-1010 6510);
PAINT MONO (-1010 6510);
FORCEPROP 2 LASTPIN (-1000 7000) $PN OB3
J 2
(-1010 7010);
DISPLAY 0.680851 (-1010 7010);
PAINT MONO (-1010 7010);
FORCEPROP 2 LASTPIN (-1000 7050) $PN OB2
J 2
(-1010 7060);
DISPLAY 0.680851 (-1010 7060);
PAINT MONO (-1010 7060);
FORCEPROP 2 LASTPIN (-1000 7100) $PN OB1
J 2
(-1010 7110);
DISPLAY 0.680851 (-1010 7110);
PAINT MONO (-1010 7110);
FORCEPROP 2 LASTPIN (300 5500) $PN A17
J 0
(310 5510);
DISPLAY 0.680851 (310 5510);
PAINT MONO (310 5510);
FORCEPROP 2 LASTPIN (300 5350) $PN A20
J 0
(310 5360);
DISPLAY 0.680851 (310 5360);
PAINT MONO (310 5360);
FORCEPROP 2 LASTPIN (300 5200) $PN A23
J 0
(310 5210);
DISPLAY 0.680851 (310 5210);
PAINT MONO (310 5210);
FORCEPROP 2 LASTPIN (300 5050) $PN A26
J 0
(310 5060);
DISPLAY 0.680851 (310 5060);
PAINT MONO (310 5060);
FORCEPROP 2 LASTPIN (300 4750) $PN A30
J 0
(310 4760);
DISPLAY 0.680851 (310 4760);
PAINT MONO (310 4760);
FORCEPROP 2 LASTPIN (300 4600) $PN A33
J 0
(310 4610);
DISPLAY 0.680851 (310 4610);
PAINT MONO (310 4610);
FORCEPROP 2 LASTPIN (300 4450) $PN A36
J 0
(310 4460);
DISPLAY 0.680851 (310 4460);
PAINT MONO (310 4460);
FORCEPROP 2 LASTPIN (300 4300) $PN A39
J 0
(310 4310);
DISPLAY 0.680851 (310 4310);
PAINT MONO (310 4310);
FORCEPROP 2 LASTPIN (300 3950) $PN A44
J 0
(310 3960);
DISPLAY 0.680851 (310 3960);
PAINT MONO (310 3960);
FORCEPROP 2 LASTPIN (300 3800) $PN A47
J 0
(310 3810);
DISPLAY 0.680851 (310 3810);
PAINT MONO (310 3810);
FORCEPROP 2 LASTPIN (300 3650) $PN A50
J 0
(310 3660);
DISPLAY 0.680851 (310 3660);
PAINT MONO (310 3660);
FORCEPROP 2 LASTPIN (300 3500) $PN A53
J 0
(310 3510);
DISPLAY 0.680851 (310 3510);
PAINT MONO (310 3510);
FORCEPROP 2 LASTPIN (300 3350) $PN A56
J 0
(310 3360);
DISPLAY 0.680851 (310 3360);
PAINT MONO (310 3360);
FORCEPROP 2 LASTPIN (300 3200) $PN A59
J 0
(310 3210);
DISPLAY 0.680851 (310 3210);
PAINT MONO (310 3210);
FORCEPROP 2 LASTPIN (300 3050) $PN A62
J 0
(310 3060);
DISPLAY 0.680851 (310 3060);
PAINT MONO (310 3060);
FORCEPROP 2 LASTPIN (300 2900) $PN A65
J 0
(310 2910);
DISPLAY 0.680851 (310 2910);
PAINT MONO (310 2910);
FORCEPROP 2 LASTPIN (300 5450) $PN A18
J 0
(310 5460);
DISPLAY 0.680851 (310 5460);
PAINT MONO (310 5460);
FORCEPROP 2 LASTPIN (300 5300) $PN A21
J 0
(310 5310);
DISPLAY 0.680851 (310 5310);
PAINT MONO (310 5310);
FORCEPROP 2 LASTPIN (300 5150) $PN A24
J 0
(310 5160);
DISPLAY 0.680851 (310 5160);
PAINT MONO (310 5160);
FORCEPROP 2 LASTPIN (300 5000) $PN A27
J 0
(310 5010);
DISPLAY 0.680851 (310 5010);
PAINT MONO (310 5010);
FORCEPROP 2 LASTPIN (300 4700) $PN A31
J 0
(310 4710);
DISPLAY 0.680851 (310 4710);
PAINT MONO (310 4710);
FORCEPROP 2 LASTPIN (300 4550) $PN A34
J 0
(310 4560);
DISPLAY 0.680851 (310 4560);
PAINT MONO (310 4560);
FORCEPROP 2 LASTPIN (300 4400) $PN A37
J 0
(310 4410);
DISPLAY 0.680851 (310 4410);
PAINT MONO (310 4410);
FORCEPROP 2 LASTPIN (300 4250) $PN A40
J 0
(310 4260);
DISPLAY 0.680851 (310 4260);
PAINT MONO (310 4260);
FORCEPROP 2 LASTPIN (300 3900) $PN A45
J 0
(310 3910);
DISPLAY 0.680851 (310 3910);
PAINT MONO (310 3910);
FORCEPROP 2 LASTPIN (300 3750) $PN A48
J 0
(310 3760);
DISPLAY 0.680851 (310 3760);
PAINT MONO (310 3760);
FORCEPROP 2 LASTPIN (300 3600) $PN A51
J 0
(310 3610);
DISPLAY 0.680851 (310 3610);
PAINT MONO (310 3610);
FORCEPROP 2 LASTPIN (300 3450) $PN A54
J 0
(310 3460);
DISPLAY 0.680851 (310 3460);
PAINT MONO (310 3460);
FORCEPROP 2 LASTPIN (300 3300) $PN A57
J 0
(310 3310);
DISPLAY 0.680851 (310 3310);
PAINT MONO (310 3310);
FORCEPROP 2 LASTPIN (300 3150) $PN A60
J 0
(310 3160);
DISPLAY 0.680851 (310 3160);
PAINT MONO (310 3160);
FORCEPROP 2 LASTPIN (300 3000) $PN A63
J 0
(310 3010);
DISPLAY 0.680851 (310 3010);
PAINT MONO (310 3010);
FORCEPROP 2 LASTPIN (300 2850) $PN A66
J 0
(310 2860);
DISPLAY 0.680851 (310 2860);
PAINT MONO (310 2860);
FORCEPROP 2 LASTPIN (-1000 5850) $PN B10
J 2
(-1010 5860);
DISPLAY 0.680851 (-1010 5860);
PAINT MONO (-1010 5860);
FORCEPROP 2 LASTPIN (300 5800) $PN A11
J 0
(310 5810);
DISPLAY 0.680851 (310 5810);
PAINT MONO (310 5810);
FORCEPROP 2 LASTPIN (300 7100) $PN OA1
J 0
(310 7110);
DISPLAY 0.680851 (310 7110);
PAINT MONO (310 7110);
FORCEPROP 2 LASTPIN (300 7050) $PN OA2
J 0
(310 7060);
DISPLAY 0.680851 (310 7060);
PAINT MONO (310 7060);
FORCEPROP 2 LASTPIN (-1000 5500) $PN B17
J 2
(-1010 5510);
DISPLAY 0.680851 (-1010 5510);
PAINT MONO (-1010 5510);
FORCEPROP 2 LASTPIN (-1000 5350) $PN B20
J 2
(-1010 5360);
DISPLAY 0.680851 (-1010 5360);
PAINT MONO (-1010 5360);
FORCEPROP 2 LASTPIN (-1000 5200) $PN B23
J 2
(-1010 5210);
DISPLAY 0.680851 (-1010 5210);
PAINT MONO (-1010 5210);
FORCEPROP 2 LASTPIN (-1000 5050) $PN B26
J 2
(-1010 5060);
DISPLAY 0.680851 (-1010 5060);
PAINT MONO (-1010 5060);
FORCEPROP 2 LASTPIN (-1000 4750) $PN B30
J 2
(-1010 4760);
DISPLAY 0.680851 (-1010 4760);
PAINT MONO (-1010 4760);
FORCEPROP 2 LASTPIN (-1000 4600) $PN B33
J 2
(-1010 4610);
DISPLAY 0.680851 (-1010 4610);
PAINT MONO (-1010 4610);
FORCEPROP 2 LASTPIN (-1000 4450) $PN B36
J 2
(-1010 4460);
DISPLAY 0.680851 (-1010 4460);
PAINT MONO (-1010 4460);
FORCEPROP 2 LASTPIN (-1000 4300) $PN B39
J 2
(-1010 4310);
DISPLAY 0.680851 (-1010 4310);
PAINT MONO (-1010 4310);
FORCEPROP 2 LASTPIN (-1000 3950) $PN B44
J 2
(-1010 3960);
DISPLAY 0.680851 (-1010 3960);
PAINT MONO (-1010 3960);
FORCEPROP 2 LASTPIN (-1000 3800) $PN B47
J 2
(-1010 3810);
DISPLAY 0.680851 (-1010 3810);
PAINT MONO (-1010 3810);
FORCEPROP 2 LASTPIN (-1000 3650) $PN B50
J 2
(-1010 3660);
DISPLAY 0.680851 (-1010 3660);
PAINT MONO (-1010 3660);
FORCEPROP 2 LASTPIN (-1000 3500) $PN B53
J 2
(-1010 3510);
DISPLAY 0.680851 (-1010 3510);
PAINT MONO (-1010 3510);
FORCEPROP 2 LASTPIN (-1000 3350) $PN B56
J 2
(-1010 3360);
DISPLAY 0.680851 (-1010 3360);
PAINT MONO (-1010 3360);
FORCEPROP 2 LASTPIN (-1000 3200) $PN B59
J 2
(-1010 3210);
DISPLAY 0.680851 (-1010 3210);
PAINT MONO (-1010 3210);
FORCEPROP 2 LASTPIN (-1000 3050) $PN B62
J 2
(-1010 3060);
DISPLAY 0.680851 (-1010 3060);
PAINT MONO (-1010 3060);
FORCEPROP 2 LASTPIN (-1000 2900) $PN B65
J 2
(-1010 2910);
DISPLAY 0.680851 (-1010 2910);
PAINT MONO (-1010 2910);
FORCEPROP 2 LASTPIN (-1000 5450) $PN B18
J 2
(-1010 5460);
DISPLAY 0.680851 (-1010 5460);
PAINT MONO (-1010 5460);
FORCEPROP 2 LASTPIN (-1000 5300) $PN B21
J 2
(-1010 5310);
DISPLAY 0.680851 (-1010 5310);
PAINT MONO (-1010 5310);
FORCEPROP 2 LASTPIN (-1000 5150) $PN B24
J 2
(-1010 5160);
DISPLAY 0.680851 (-1010 5160);
PAINT MONO (-1010 5160);
FORCEPROP 2 LASTPIN (-1000 5000) $PN B27
J 2
(-1010 5010);
DISPLAY 0.680851 (-1010 5010);
PAINT MONO (-1010 5010);
FORCEPROP 2 LASTPIN (-1000 4700) $PN B31
J 2
(-1010 4710);
DISPLAY 0.680851 (-1010 4710);
PAINT MONO (-1010 4710);
FORCEPROP 2 LASTPIN (-1000 4550) $PN B34
J 2
(-1010 4560);
DISPLAY 0.680851 (-1010 4560);
PAINT MONO (-1010 4560);
FORCEPROP 2 LASTPIN (-1000 4400) $PN B37
J 2
(-1010 4410);
DISPLAY 0.680851 (-1010 4410);
PAINT MONO (-1010 4410);
FORCEPROP 2 LASTPIN (-1000 4250) $PN B40
J 2
(-1010 4260);
DISPLAY 0.680851 (-1010 4260);
PAINT MONO (-1010 4260);
FORCEPROP 2 LASTPIN (-1000 3900) $PN B45
J 2
(-1010 3910);
DISPLAY 0.680851 (-1010 3910);
PAINT MONO (-1010 3910);
FORCEPROP 2 LASTPIN (-1000 3750) $PN B48
J 2
(-1010 3760);
DISPLAY 0.680851 (-1010 3760);
PAINT MONO (-1010 3760);
FORCEPROP 2 LASTPIN (-1000 3600) $PN B51
J 2
(-1010 3610);
DISPLAY 0.680851 (-1010 3610);
PAINT MONO (-1010 3610);
FORCEPROP 2 LASTPIN (-1000 3450) $PN B54
J 2
(-1010 3460);
DISPLAY 0.680851 (-1010 3460);
PAINT MONO (-1010 3460);
FORCEPROP 2 LASTPIN (-1000 3300) $PN B57
J 2
(-1010 3310);
DISPLAY 0.680851 (-1010 3310);
PAINT MONO (-1010 3310);
FORCEPROP 2 LASTPIN (-1000 3150) $PN B60
J 2
(-1010 3160);
DISPLAY 0.680851 (-1010 3160);
PAINT MONO (-1010 3160);
FORCEPROP 2 LASTPIN (-1000 3000) $PN B63
J 2
(-1010 3010);
DISPLAY 0.680851 (-1010 3010);
PAINT MONO (-1010 3010);
FORCEPROP 2 LASTPIN (-1000 2850) $PN B66
J 2
(-1010 2860);
DISPLAY 0.680851 (-1010 2860);
PAINT MONO (-1010 2860);
FORCEPROP 2 LASTPIN (300 5850) $PN A10
J 0
(310 5860);
DISPLAY 0.680851 (310 5860);
PAINT MONO (310 5860);
FORCEPROP 2 LASTPIN (-1000 4150) $PN B42
J 2
(-1010 4160);
DISPLAY 0.680851 (-1010 4160);
PAINT MONO (-1010 4160);
FORCEPROP 2 LASTPIN (300 4150) $PN A42
J 0
(310 4160);
DISPLAY 0.680851 (310 4160);
PAINT MONO (310 4160);
FORCEPROP 2 LASTPIN (300 5750) $PN A12
J 0
(310 5760);
DISPLAY 0.680851 (310 5760);
PAINT MONO (310 5760);
FORCEPROP 2 LASTPIN (-1000 2650) $PN B70
J 2
(-1010 2660);
DISPLAY 0.680851 (-1010 2660);
PAINT MONO (-1010 2660);
FORCEPROP 2 LASTPIN (300 2650) $PN A70
J 0
(310 2660);
DISPLAY 0.680851 (310 2660);
PAINT MONO (310 2660);
FORCEPROP 2 LASTPIN (300 6950) $PN OA4
J 0
(310 6960);
DISPLAY 0.680851 (310 6960);
PAINT MONO (310 6960);
FORCEPROP 2 LASTPIN (300 6900) $PN OA5
J 0
(310 6910);
DISPLAY 0.680851 (310 6910);
PAINT MONO (310 6910);
FORCEPROP 2 LASTPIN (300 6450) $PN OA14
J 0
(310 6460);
DISPLAY 0.680851 (310 6460);
PAINT MONO (310 6460);
FORCEPROP 2 LASTPIN (-1000 6450) $PN OB14
J 2
(-1010 6460);
DISPLAY 0.680851 (-1010 6460);
PAINT MONO (-1010 6460);
FORCEPROP 2 LASTPIN (-1000 6700) $PN OB9
J 2
(-1010 6710);
DISPLAY 0.680851 (-1010 6710);
PAINT MONO (-1010 6710);
FORCEPROP 2 LASTPIN (-1000 6750) $PN OB8
J 2
(-1010 6760);
DISPLAY 0.680851 (-1010 6760);
PAINT MONO (-1010 6760);
FORCEPROP 2 LASTPIN (300 6800) $PN OA7
J 0
(310 6810);
DISPLAY 0.680851 (310 6810);
PAINT MONO (310 6810);
FORCEPROP 2 LASTPIN (300 6700) $PN OA9
J 0
(310 6710);
DISPLAY 0.680851 (310 6710);
PAINT MONO (310 6710);
FORCEPROP 2 LASTPIN (300 6750) $PN OA8
J 0
(310 6760);
DISPLAY 0.680851 (310 6760);
PAINT MONO (310 6760);
FORCEPROP 2 LASTPIN (-1000 5650) $PN B14
J 2
(-1010 5660);
DISPLAY 0.680851 (-1010 5660);
PAINT MONO (-1010 5660);
FORCEPROP 2 LASTPIN (300 5650) $PN A14
J 0
(310 5660);
DISPLAY 0.680851 (310 5660);
PAINT MONO (310 5660);
FORCEPROP 2 LASTPIN (-1000 6600) $PN OB11
J 2
(-1010 6610);
DISPLAY 0.680851 (-1010 6610);
PAINT MONO (-1010 6610);
FORCEPROP 2 LASTPIN (300 6600) $PN OA11
J 0
(310 6610);
DISPLAY 0.680851 (310 6610);
PAINT MONO (310 6610);
FORCEPROP 2 LASTPIN (-1000 5600) $PN B15
J 2
(-1010 5610);
DISPLAY 0.680851 (-1010 5610);
PAINT MONO (-1010 5610);
FORCEPROP 2 LASTPIN (300 5600) $PN A15
J 0
(310 5610);
DISPLAY 0.680851 (310 5610);
PAINT MONO (310 5610);
FORCEPROP 2 LASTPIN (-1000 6550) $PN OB12
J 2
(-1010 6560);
DISPLAY 0.680851 (-1010 6560);
PAINT MONO (-1010 6560);
FORCEPROP 2 LASTPIN (300 6550) $PN OA12
J 0
(310 6560);
DISPLAY 0.680851 (310 6560);
PAINT MONO (310 6560);
FORCEPROP 2 LASTPIN (-1000 2750) $PN B68
J 2
(-1010 2760);
DISPLAY 0.680851 (-1010 2760);
PAINT MONO (-1010 2760);
FORCEPROP 2 LASTPIN (-1000 2700) $PN B69
J 2
(-1010 2710);
DISPLAY 0.680851 (-1010 2710);
PAINT MONO (-1010 2710);
FORCEPROP 2 LASTPIN (-1000 6800) $PN OB7
J 2
(-1010 6810);
DISPLAY 0.680851 (-1010 6810);
PAINT MONO (-1010 6810);
FORCEPROP 2 LASTPIN (300 6850) $PN OA6
J 0
(310 6860);
DISPLAY 0.680851 (310 6860);
PAINT MONO (310 6860);
FORCEPROP 2 LASTPIN (300 6000) $PN A7
J 0
(310 6010);
DISPLAY 0.680851 (310 6010);
PAINT MONO (310 6010);
FORCEPROP 2 LASTPIN (300 5950) $PN A8
J 0
(310 5960);
DISPLAY 0.680851 (310 5960);
PAINT MONO (310 5960);
FORCEPROP 2 LASTPIN (300 5900) $PN A9
J 0
(310 5910);
DISPLAY 0.680851 (310 5910);
PAINT MONO (310 5910);
FORCEPROP 2 LASTPIN (300 2750) $PN A68
J 0
(310 2760);
DISPLAY 0.680851 (310 2760);
PAINT MONO (310 2760);
FORCEPROP 2 LASTPIN (300 2700) $PN A69
J 0
(310 2710);
DISPLAY 0.680851 (310 2710);
PAINT MONO (310 2710);
FORCEPROP 2 LASTPIN (300 7000) $PN OA3
J 0
(310 7010);
DISPLAY 0.680851 (310 7010);
PAINT MONO (310 7010);
FORCEPROP 2 LAST PART_TYPE SMLF
J 0
(-825 7600);
DISPLAY 1.021277 (-825 7600);
FORCEPROP 1 LAST MATERIAL IO
J 0
(-839 7218);
DISPLAY 0.723404 (-839 7218);
PAINT GREEN (-839 7218);
FORCEPROP 2 LAST VALUE SCONN168_ME1016810202011
J 0
(-825 7550);
DISPLAY 1.021277 (-825 7550);
FORCEPROP 2 LAST SEC_TYPE 
J 0
(-825 7650);
DISPLAY 1.021277 (-825 7650);
DISPLAY INVISIBLE (-825 7650);
FORCEPROP 2 LAST CDS_LIB pure_quanta
J 0
(-350 4725);
DISPLAY INVISIBLE (-350 4725);
FORCEPROP 1 LAST CDS_LMAN_SYM_OUTLINE -500,2475,500,-2475
J 0
(-350 4725);
DISPLAY 0.468085 (-350 4725);
PAINT GREEN (-350 4725);
DISPLAY INVISIBLE (-350 4725);
FORCEPROP 1 LAST NEEDS_NO_SIZE TRUE
J 0
(-350 4725);
DISPLAY 0.723404 (-350 4725);
PAINT GREEN (-350 4725);
DISPLAY INVISIBLE (-350 4725);
FORCEPROP 1 LAST PATH I168
J 0
(-350 4725);
DISPLAY 0.723404 (-350 4725);
PAINT GREEN (-350 4725);
DISPLAY INVISIBLE (-350 4725);
FORCEPROP 1 LAST PART_NUMBER DFHSG8FR011
J 0
(-839 7345);
DISPLAY 0.723404 (-839 7345);
PAINT GREEN (-839 7345);
DISPLAY INVISIBLE (-839 7345);
FORCEADD Q_RES..2
(3125 5600);
FORCEPROP 1 LAST LOCATION R1895
J 0
(3170 5725);
DISPLAY 0.978723 (3170 5725);
FORCEPROP 0 LAST $SEC 1
J 0
(3175 5775);
DISPLAY 0.680851 (3175 5775);
PAINT MONO (3175 5775);
DISPLAY INVISIBLE (3175 5775);
FORCEPROP 0 LAST CDS_SEC 1
J 0
(3175 5775);
DISPLAY 0.680851 (3175 5775);
DISPLAY INVISIBLE (3175 5775);
FORCEPROP 1 LASTPIN (3125 5700) $PN 1
J 0
(3130 5662);
DISPLAY 0.787234 (3130 5662);
PAINT MONO (3130 5662);
FORCEPROP 1 LASTPIN (3125 5500) $PN 2
J 0
(3130 5510);
DISPLAY 0.787234 (3130 5510);
PAINT MONO (3130 5510);
FORCEPROP 1 LAST WATTAGE 1/16W
J 0
(3165 5575);
DISPLAY 0.978723 (3165 5575);
FORCEPROP 1 LAST MATERIAL CHIP
J 0
(3165 5525);
DISPLAY 0.978723 (3165 5525);
FORCEPROP 1 LAST TOLERANCE 5%
J 0
(3170 5625);
DISPLAY 0.978723 (3170 5625);
FORCEPROP 1 LAST VALUE 0
J 0
(3170 5675);
DISPLAY 0.978723 (3170 5675);
FORCEPROP 1 LAST PACK_TYPE 0402LF
J 0
(3165 5425);
DISPLAY 0.978723 (3165 5425);
FORCEPROP 2 LAST CDS_LIB pure_quanta
J 0
(3125 5600);
DISPLAY INVISIBLE (3125 5600);
FORCEPROP 1 LAST PATH I169
J 0
(3175 5775);
DISPLAY 0.978723 (3175 5775);
PAINT WHITE (3175 5775);
DISPLAY INVISIBLE (3175 5775);
FORCEPROP 1 LAST PART_NUMBER CS00002JB13
J 0
(3165 5475);
DISPLAY 0.978723 (3165 5475);
DISPLAY INVISIBLE (3165 5475);
FORCEADD Q_RES..2
(-3825 2250);
FORCEPROP 1 LAST LOCATION R33
J 0
(-3780 2375);
DISPLAY 0.978723 (-3780 2375);
FORCEPROP 2 LAST $SEC 1
J 0
(-3775 2475);
DISPLAY 0.680851 (-3775 2475);
PAINT MONO (-3775 2475);
DISPLAY INVISIBLE (-3775 2475);
FORCEPROP 2 LAST CDS_SEC 1
J 0
(-3775 2475);
DISPLAY 1.021277 (-3775 2475);
DISPLAY INVISIBLE (-3775 2475);
FORCEPROP 1 LASTPIN (-3825 2350) $PN 1
J 0
(-3820 2312);
DISPLAY 0.787234 (-3820 2312);
FORCEPROP 1 LASTPIN (-3825 2150) $PN 2
J 0
(-3820 2160);
DISPLAY 0.787234 (-3820 2160);
FORCEPROP 1 LAST PACK_TYPE 0402LF
J 0
(-3785 2075);
DISPLAY 0.787234 (-3785 2075);
FORCEPROP 1 LAST MATERIAL EMPTY
J 0
(-3785 2175);
DISPLAY 0.787234 (-3785 2175);
FORCEPROP 1 LAST WATTAGE 1/16W
J 0
(-3785 2225);
DISPLAY 0.787234 (-3785 2225);
FORCEPROP 1 LAST VALUE 4.7K
J 0
(-3780 2325);
DISPLAY 0.787234 (-3780 2325);
FORCEPROP 1 LAST TOLERANCE 1%
J 0
(-3780 2275);
DISPLAY 0.787234 (-3780 2275);
FORCEPROP 2 LAST CDS_LIB pure_quanta
J 0
(-3825 2250);
PAINT MONO (-3825 2250);
DISPLAY INVISIBLE (-3825 2250);
FORCEPROP 1 LAST PATH I17
J 0
(-3775 2425);
DISPLAY 0.978723 (-3775 2425);
PAINT WHITE (-3775 2425);
DISPLAY INVISIBLE (-3775 2425);
FORCEPROP 1 LAST PART_NUMBER CS24702FB06
J 0
(-3785 2125);
DISPLAY 0.787234 (-3785 2125);
DISPLAY INVISIBLE (-3785 2125);
FORCEADD Q_RES..1
(1775 5950);
FORCEPROP 1 LAST LOCATION R48
J 0
(1550 5950);
DISPLAY 0.808511 (1550 5950);
FORCEPROP 2 LAST SEC 1
J 0
(1725 6150);
DISPLAY 0.680851 (1725 6150);
PAINT MONO (1725 6150);
DISPLAY INVISIBLE (1725 6150);
FORCEPROP 1 LASTPIN (1675 5950) $PN 1
J 0
(1687 5962);
DISPLAY 0.510638 (1687 5962);
PAINT MONO (1687 5962);
FORCEPROP 1 LASTPIN (1875 5950) $PN 2
J 0
(1837 5962);
DISPLAY 0.510638 (1837 5962);
PAINT MONO (1837 5962);
FORCEPROP 1 LAST WATTAGE 1/16W
J 2
(2350 5925);
DISPLAY 0.510638 (2350 5925);
FORCEPROP 1 LAST MATERIAL CHIP
J 0
(1825 5925);
DISPLAY 0.510638 (1825 5925);
FORCEPROP 1 LAST PACK_TYPE 0402LF
J 0
(2100 5950);
DISPLAY 0.510638 (2100 5950);
FORCEPROP 1 LAST VALUE 200
J 2
(2000 5950);
DISPLAY 0.510638 (2000 5950);
FORCEPROP 1 LAST TOLERANCE 1%
J 0
(2025 5950);
DISPLAY 0.510638 (2025 5950);
FORCEPROP 2 LAST CDS_LIB pure_quanta
J 0
(1775 5950);
DISPLAY INVISIBLE (1775 5950);
FORCEPROP 2 LAST SEC_TYPE 0402LF
J 0
(1725 6150);
DISPLAY 0.680851 (1725 6150);
DISPLAY INVISIBLE (1725 6150);
FORCEPROP 1 LAST PATH I170
J 0
(1725 6100);
DISPLAY 0.978723 (1725 6100);
PAINT WHITE (1725 6100);
DISPLAY INVISIBLE (1725 6100);
FORCEPROP 1 LAST PART_NUMBER CS12002FB06
J 0
(1950 5925);
DISPLAY 0.510638 (1950 5925);
DISPLAY INVISIBLE (1950 5925);
FORCEADD Q_RES..1
(1775 6000);
FORCEPROP 1 LAST LOCATION R47
J 0
(1550 6000);
DISPLAY 0.808511 (1550 6000);
FORCEPROP 2 LAST SEC 1
J 0
(1725 6200);
DISPLAY 0.680851 (1725 6200);
PAINT MONO (1725 6200);
DISPLAY INVISIBLE (1725 6200);
FORCEPROP 1 LASTPIN (1675 6000) $PN 1
J 0
(1687 6012);
DISPLAY 0.638298 (1687 6012);
PAINT MONO (1687 6012);
FORCEPROP 1 LASTPIN (1875 6000) $PN 2
J 0
(1837 6012);
DISPLAY 0.638298 (1837 6012);
PAINT MONO (1837 6012);
FORCEPROP 1 LAST MATERIAL CHIP
J 0
(1625 6075);
DISPLAY 0.510638 (1625 6075);
FORCEPROP 1 LAST PACK_TYPE 0402LF
J 0
(2100 6000);
DISPLAY 0.510638 (2100 6000);
FORCEPROP 1 LAST WATTAGE 1/16W
J 2
(1875 6075);
DISPLAY 0.510638 (1875 6075);
FORCEPROP 1 LAST VALUE 200
J 2
(2000 6000);
DISPLAY 0.510638 (2000 6000);
FORCEPROP 1 LAST TOLERANCE 1%
J 0
(2025 6000);
DISPLAY 0.510638 (2025 6000);
FORCEPROP 2 LAST CDS_LIB pure_quanta
J 0
(1775 6000);
DISPLAY INVISIBLE (1775 6000);
FORCEPROP 2 LAST SEC_TYPE 0402LF
J 0
(1725 6200);
DISPLAY 0.680851 (1725 6200);
DISPLAY INVISIBLE (1725 6200);
FORCEPROP 1 LAST PATH I171
J 0
(1725 6150);
DISPLAY 0.978723 (1725 6150);
PAINT WHITE (1725 6150);
DISPLAY INVISIBLE (1725 6150);
FORCEPROP 1 LAST PART_NUMBER CS12002FB06
J 0
(1625 6100);
DISPLAY 0.510638 (1625 6100);
DISPLAY INVISIBLE (1625 6100);
FORCEADD OFFPAGE..5
(-2775 2650);
FORCEPROP 2 LAST $XR1 143 
J 0
(-3150 2650);
DISPLAY 0.638298 (-3150 2650);
PAINT MONO (-3150 2650);
FORCEPROP 2 LAST $XR0 134 
J 0
(-3030 2650);
DISPLAY 0.638298 (-3030 2650);
PAINT MONO (-3030 2650);
FORCEPROP 2 LAST CDS_LIB standard
J 0
(-2775 2650);
PAINT MONO (-2775 2650);
DISPLAY INVISIBLE (-2775 2650);
FORCEPROP 1 LAST OFFPAGE TRUE
J 0
(-2450 2525);
DISPLAY 0.872340 (-2450 2525);
PAINT GREEN (-2450 2525);
DISPLAY INVISIBLE (-2450 2525);
FORCEPROP 1 LAST COMMENT_BODY TRUE
J 0
(-2675 2575);
DISPLAY 0.872340 (-2675 2575);
PAINT GREEN (-2675 2575);
DISPLAY INVISIBLE (-2675 2575);
FORCEPROP 2 LAST PATH I18
J 0
(-3050 2700);
DISPLAY 0.680851 (-3050 2700);
DISPLAY INVISIBLE (-3050 2700);
FORCEADD Q_RES..1
(-750 1450);
FORCEPROP 1 LAST LOCATION R8422
J 0
(-950 1450);
DISPLAY 0.638298 (-950 1450);
FORCEPROP 0 LAST $SEC 1
J 0
(-950 1500);
DISPLAY 0.680851 (-950 1500);
PAINT MONO (-950 1500);
DISPLAY INVISIBLE (-950 1500);
FORCEPROP 0 LAST CDS_SEC 1
J 0
(-950 1500);
DISPLAY 1.021277 (-950 1500);
DISPLAY INVISIBLE (-950 1500);
FORCEPROP 1 LASTPIN (-850 1450) $PN 1
J 0
(-838 1462);
DISPLAY 0.787234 (-838 1462);
PAINT MONO (-838 1462);
FORCEPROP 1 LASTPIN (-650 1450) $PN 2
J 0
(-688 1462);
DISPLAY 0.787234 (-688 1462);
PAINT MONO (-688 1462);
FORCEPROP 1 LAST MATERIAL CHIP
J 0
(-475 1450);
DISPLAY 0.510638 (-475 1450);
FORCEPROP 1 LAST TOLERANCE 1%
J 0
(-550 1450);
DISPLAY 0.510638 (-550 1450);
FORCEPROP 1 LAST VALUE 10K
J 2
(-575 1450);
DISPLAY 0.510638 (-575 1450);
FORCEPROP 2 LAST CDS_LIB pure_quanta
J 0
(-750 1450);
DISPLAY INVISIBLE (-750 1450);
FORCEPROP 1 LAST PACK_TYPE 0402LF
J 0
(-925 1575);
DISPLAY 0.510638 (-925 1575);
DISPLAY INVISIBLE (-925 1575);
FORCEPROP 1 LAST WATTAGE 1/16W
J 2
(-550 1575);
DISPLAY 0.510638 (-550 1575);
DISPLAY INVISIBLE (-550 1575);
FORCEPROP 1 LAST PATH I19
J 0
(-800 1600);
DISPLAY 0.978723 (-800 1600);
PAINT WHITE (-800 1600);
DISPLAY INVISIBLE (-800 1600);
FORCEPROP 1 LAST PART_NUMBER CS31002FB08
J 0
(-925 1525);
DISPLAY 0.510638 (-925 1525);
DISPLAY INVISIBLE (-925 1525);
FORCEADD Q_RES..2
(-4300 1725);
FORCEPROP 1 LAST LOCATION R32
J 0
(-4255 1850);
DISPLAY 0.978723 (-4255 1850);
FORCEPROP 2 LAST $SEC 1
J 0
(-4250 1950);
DISPLAY 0.680851 (-4250 1950);
PAINT MONO (-4250 1950);
DISPLAY INVISIBLE (-4250 1950);
FORCEPROP 2 LAST CDS_SEC 1
J 0
(-4250 1950);
DISPLAY 1.021277 (-4250 1950);
DISPLAY INVISIBLE (-4250 1950);
FORCEPROP 1 LASTPIN (-4300 1825) $PN 1
J 0
(-4295 1787);
DISPLAY 0.787234 (-4295 1787);
FORCEPROP 1 LASTPIN (-4300 1625) $PN 2
J 0
(-4295 1635);
DISPLAY 0.787234 (-4295 1635);
FORCEPROP 1 LAST PACK_TYPE 0402LF
J 0
(-4260 1550);
DISPLAY 0.787234 (-4260 1550);
FORCEPROP 1 LAST MATERIAL CHIP
J 0
(-4260 1650);
DISPLAY 0.787234 (-4260 1650);
FORCEPROP 1 LAST TOLERANCE 1%
J 0
(-4255 1750);
DISPLAY 0.787234 (-4255 1750);
FORCEPROP 1 LAST WATTAGE 1/16W
J 0
(-4260 1700);
DISPLAY 0.787234 (-4260 1700);
FORCEPROP 1 LAST VALUE 4.7K
J 0
(-4255 1800);
DISPLAY 0.787234 (-4255 1800);
FORCEPROP 2 LAST CDS_LIB pure_quanta
J 0
(-4300 1725);
PAINT MONO (-4300 1725);
DISPLAY INVISIBLE (-4300 1725);
FORCEPROP 1 LAST PATH I2
J 0
(-4250 1900);
DISPLAY 0.978723 (-4250 1900);
PAINT WHITE (-4250 1900);
DISPLAY INVISIBLE (-4250 1900);
FORCEPROP 1 LAST PART_NUMBER CS24702FB06
J 0
(-4260 1600);
DISPLAY 0.787234 (-4260 1600);
DISPLAY INVISIBLE (-4260 1600);
FORCEADD Q_RES..1
(-750 1625);
FORCEPROP 1 LAST LOCATION R8423
J 0
(-950 1625);
DISPLAY 0.638298 (-950 1625);
FORCEPROP 0 LAST $SEC 1
J 0
(-500 1750);
DISPLAY 0.680851 (-500 1750);
PAINT MONO (-500 1750);
DISPLAY INVISIBLE (-500 1750);
FORCEPROP 0 LAST CDS_SEC 1
J 0
(-500 1750);
DISPLAY 1.021277 (-500 1750);
DISPLAY INVISIBLE (-500 1750);
FORCEPROP 1 LASTPIN (-850 1625) $PN 1
J 0
(-838 1637);
DISPLAY 0.787234 (-838 1637);
PAINT MONO (-838 1637);
FORCEPROP 1 LASTPIN (-650 1625) $PN 2
J 0
(-688 1637);
DISPLAY 0.787234 (-688 1637);
PAINT MONO (-688 1637);
FORCEPROP 1 LAST TOLERANCE 1%
J 0
(-500 1625);
DISPLAY 0.638298 (-500 1625);
FORCEPROP 1 LAST VALUE 1K
J 2
(-550 1625);
DISPLAY 0.638298 (-550 1625);
FORCEPROP 1 LAST PACK_TYPE 0402LF
J 0
(-800 1725);
DISPLAY 0.510638 (-800 1725);
FORCEPROP 1 LAST WATTAGE 1/16W
J 2
(-500 1725);
DISPLAY 0.510638 (-500 1725);
FORCEPROP 1 LAST MATERIAL CHIP
J 0
(-375 1625);
DISPLAY 0.638298 (-375 1625);
FORCEPROP 2 LAST CDS_LIB pure_quanta
J 0
(-750 1625);
DISPLAY INVISIBLE (-750 1625);
FORCEPROP 1 LAST PATH I20
J 0
(-800 1775);
DISPLAY 0.978723 (-800 1775);
PAINT WHITE (-800 1775);
DISPLAY INVISIBLE (-800 1775);
FORCEPROP 1 LAST PART_NUMBER CS21002FB06
J 0
(-800 1675);
DISPLAY 0.510638 (-800 1675);
DISPLAY INVISIBLE (-800 1675);
FORCEADD Q_RES..1
(-750 1800);
FORCEPROP 1 LAST LOCATION R8421
J 0
(-950 1800);
DISPLAY 0.638298 (-950 1800);
FORCEPROP 0 LAST $SEC 1
J 0
(-950 1850);
DISPLAY 0.680851 (-950 1850);
PAINT MONO (-950 1850);
DISPLAY INVISIBLE (-950 1850);
FORCEPROP 0 LAST CDS_SEC 1
J 0
(-950 1850);
DISPLAY 1.021277 (-950 1850);
DISPLAY INVISIBLE (-950 1850);
FORCEPROP 1 LASTPIN (-850 1800) $PN 1
J 0
(-838 1812);
DISPLAY 0.787234 (-838 1812);
PAINT MONO (-838 1812);
FORCEPROP 1 LASTPIN (-650 1800) $PN 2
J 0
(-688 1812);
DISPLAY 0.787234 (-688 1812);
PAINT MONO (-688 1812);
FORCEPROP 1 LAST TOLERANCE 1%
J 0
(-550 1800);
DISPLAY 0.510638 (-550 1800);
FORCEPROP 1 LAST VALUE 10K
J 2
(-575 1800);
DISPLAY 0.510638 (-575 1800);
FORCEPROP 1 LAST MATERIAL CHIP
J 0
(-475 1800);
DISPLAY 0.510638 (-475 1800);
FORCEPROP 1 LAST PACK_TYPE 0402LF
J 0
(-925 1925);
DISPLAY 0.510638 (-925 1925);
DISPLAY INVISIBLE (-925 1925);
FORCEPROP 1 LAST WATTAGE 1/16W
J 2
(-550 1925);
DISPLAY 0.510638 (-550 1925);
DISPLAY INVISIBLE (-550 1925);
FORCEPROP 2 LAST CDS_LIB pure_quanta
J 0
(-750 1800);
DISPLAY INVISIBLE (-750 1800);
FORCEPROP 1 LAST PATH I21
J 0
(-800 1950);
DISPLAY 0.978723 (-800 1950);
PAINT WHITE (-800 1950);
DISPLAY INVISIBLE (-800 1950);
FORCEPROP 1 LAST PART_NUMBER CS31002FB08
J 0
(-925 1875);
DISPLAY 0.510638 (-925 1875);
DISPLAY INVISIBLE (-925 1875);
FORCEADD Q_RES..1
(-750 1975);
FORCEPROP 1 LAST LOCATION R8420
J 0
(-950 1975);
DISPLAY 0.638298 (-950 1975);
FORCEPROP 0 LAST $SEC 1
J 0
(-500 2100);
DISPLAY 0.680851 (-500 2100);
PAINT MONO (-500 2100);
DISPLAY INVISIBLE (-500 2100);
FORCEPROP 0 LAST CDS_SEC 1
J 0
(-500 2100);
DISPLAY 1.021277 (-500 2100);
DISPLAY INVISIBLE (-500 2100);
FORCEPROP 1 LASTPIN (-850 1975) $PN 1
J 0
(-838 1987);
DISPLAY 0.787234 (-838 1987);
PAINT MONO (-838 1987);
FORCEPROP 1 LASTPIN (-650 1975) $PN 2
J 0
(-688 1987);
DISPLAY 0.787234 (-688 1987);
PAINT MONO (-688 1987);
FORCEPROP 1 LAST VALUE 1K
J 2
(-550 1975);
DISPLAY 0.638298 (-550 1975);
FORCEPROP 1 LAST WATTAGE 1/16W
J 2
(-500 2075);
DISPLAY 0.510638 (-500 2075);
FORCEPROP 1 LAST PACK_TYPE 0402LF
J 0
(-800 2075);
DISPLAY 0.510638 (-800 2075);
FORCEPROP 1 LAST TOLERANCE 1%
J 0
(-500 1975);
DISPLAY 0.638298 (-500 1975);
FORCEPROP 1 LAST MATERIAL CHIP
J 0
(-375 1975);
DISPLAY 0.638298 (-375 1975);
FORCEPROP 2 LAST CDS_LIB pure_quanta
J 0
(-750 1975);
DISPLAY INVISIBLE (-750 1975);
FORCEPROP 1 LAST PATH I22
J 0
(-800 2125);
DISPLAY 0.978723 (-800 2125);
PAINT WHITE (-800 2125);
DISPLAY INVISIBLE (-800 2125);
FORCEPROP 1 LAST PART_NUMBER CS21002FB06
J 0
(-800 2025);
DISPLAY 0.510638 (-800 2025);
DISPLAY INVISIBLE (-800 2025);
FORCEADD UNIVERSAL_GND..1
(-200 1325);
FORCEPROP 3 LASTPIN (-200 1375) SIG_NAME GND\g
J 0
(-190 1385);
DISPLAY 0.659574 (-190 1385);
PAINT MONO (-190 1385);
DISPLAY INVISIBLE (-190 1385);
FORCEPROP 2 LAST ROOM IO_SLOT
J 1
(-425 1400);
DISPLAY 0.744681 (-425 1400);
FORCEPROP 2 LAST CDS_LIB pure_quanta_power
J 0
(-200 1325);
PAINT MONO (-200 1325);
DISPLAY INVISIBLE (-200 1325);
FORCEPROP 1 LAST HDL_POWER GND
J 1
(-175 1250);
DISPLAY 0.872340 (-175 1250);
PAINT GREEN (-175 1250);
DISPLAY INVISIBLE (-175 1250);
FORCEPROP 1 LAST PATH I23
J 0
(-125 1325);
DISPLAY 0.872340 (-125 1325);
PAINT AQUA (-125 1325);
DISPLAY INVISIBLE (-125 1325);
FORCEADD TAP..1
R 2
(-1725 2850);
FORCEPROP 3 LASTPIN (-1675 2850) SIG_NAME P5E_CPU0_G3_TX_C_DN<15>
J 0
(-1665 2860);
DISPLAY 0.659574 (-1665 2860);
PAINT MONO (-1665 2860);
DISPLAY INVISIBLE (-1665 2860);
FORCEPROP 1 LASTPIN (-1675 2850) BN 15
J 2
(-1663 2858);
DISPLAY 0.680851 (-1663 2858);
PAINT GREEN (-1663 2858);
FORCEPROP 2 LAST CDS_LIB standard
J 0
(-1725 2850);
PAINT MONO (-1725 2850);
DISPLAY INVISIBLE (-1725 2850);
FORCEPROP 1 LAST BODY_TYPE PLUMBING
J 2
(-1725 2900);
DISPLAY 0.872340 (-1725 2900);
PAINT GREEN (-1725 2900);
DISPLAY INVISIBLE (-1725 2900);
FORCEPROP 1 LAST HDL_TAP TRUE
J 2
(-2050 2725);
DISPLAY 0.872340 (-2050 2725);
PAINT GREEN (-2050 2725);
DISPLAY INVISIBLE (-2050 2725);
FORCEPROP 1 LAST PATH I24
J 2
(-1723 2850);
DISPLAY 0.872340 (-1723 2850);
PAINT GREEN (-1723 2850);
DISPLAY INVISIBLE (-1723 2850);
FORCEADD TAP..1
R 2
(-1725 3000);
FORCEPROP 3 LASTPIN (-1675 3000) SIG_NAME P5E_CPU0_G3_TX_C_DN<14>
J 0
(-1665 3010);
DISPLAY 0.659574 (-1665 3010);
PAINT MONO (-1665 3010);
DISPLAY INVISIBLE (-1665 3010);
FORCEPROP 1 LASTPIN (-1675 3000) BN 14
J 2
(-1663 3008);
DISPLAY 0.680851 (-1663 3008);
PAINT GREEN (-1663 3008);
FORCEPROP 2 LAST CDS_LIB standard
J 0
(-1725 3000);
PAINT MONO (-1725 3000);
DISPLAY INVISIBLE (-1725 3000);
FORCEPROP 1 LAST BODY_TYPE PLUMBING
J 2
(-1725 3050);
DISPLAY 0.872340 (-1725 3050);
PAINT GREEN (-1725 3050);
DISPLAY INVISIBLE (-1725 3050);
FORCEPROP 1 LAST HDL_TAP TRUE
J 2
(-2050 2875);
DISPLAY 0.872340 (-2050 2875);
PAINT GREEN (-2050 2875);
DISPLAY INVISIBLE (-2050 2875);
FORCEPROP 1 LAST PATH I25
J 2
(-1723 3000);
DISPLAY 0.872340 (-1723 3000);
PAINT GREEN (-1723 3000);
DISPLAY INVISIBLE (-1723 3000);
FORCEADD TAP..1
R 2
(-1575 3050);
FORCEPROP 3 LASTPIN (-1525 3050) SIG_NAME P5E_CPU0_G3_TX_C_DP<14>
J 0
(-1515 3060);
DISPLAY 0.659574 (-1515 3060);
PAINT MONO (-1515 3060);
DISPLAY INVISIBLE (-1515 3060);
FORCEPROP 1 LASTPIN (-1525 3050) BN 14
J 2
(-1513 3058);
DISPLAY 0.680851 (-1513 3058);
PAINT GREEN (-1513 3058);
FORCEPROP 2 LAST CDS_LIB standard
J 0
(-1575 3050);
PAINT MONO (-1575 3050);
DISPLAY INVISIBLE (-1575 3050);
FORCEPROP 1 LAST BODY_TYPE PLUMBING
J 2
(-1575 3100);
DISPLAY 0.872340 (-1575 3100);
PAINT GREEN (-1575 3100);
DISPLAY INVISIBLE (-1575 3100);
FORCEPROP 1 LAST HDL_TAP TRUE
J 2
(-1900 2925);
DISPLAY 0.872340 (-1900 2925);
PAINT GREEN (-1900 2925);
DISPLAY INVISIBLE (-1900 2925);
FORCEPROP 1 LAST PATH I26
J 2
(-1573 3050);
DISPLAY 0.872340 (-1573 3050);
PAINT GREEN (-1573 3050);
DISPLAY INVISIBLE (-1573 3050);
FORCEADD TAP..1
R 2
(-1575 2900);
FORCEPROP 3 LASTPIN (-1525 2900) SIG_NAME P5E_CPU0_G3_TX_C_DP<15>
J 0
(-1515 2910);
DISPLAY 0.659574 (-1515 2910);
PAINT MONO (-1515 2910);
DISPLAY INVISIBLE (-1515 2910);
FORCEPROP 1 LASTPIN (-1525 2900) BN 15
J 2
(-1513 2908);
DISPLAY 0.680851 (-1513 2908);
PAINT GREEN (-1513 2908);
FORCEPROP 2 LAST CDS_LIB standard
J 0
(-1575 2900);
PAINT MONO (-1575 2900);
DISPLAY INVISIBLE (-1575 2900);
FORCEPROP 1 LAST BODY_TYPE PLUMBING
J 2
(-1575 2950);
DISPLAY 0.872340 (-1575 2950);
PAINT GREEN (-1575 2950);
DISPLAY INVISIBLE (-1575 2950);
FORCEPROP 1 LAST HDL_TAP TRUE
J 2
(-1900 2775);
DISPLAY 0.872340 (-1900 2775);
PAINT GREEN (-1900 2775);
DISPLAY INVISIBLE (-1900 2775);
FORCEPROP 1 LAST PATH I27
J 2
(-1573 2900);
DISPLAY 0.872340 (-1573 2900);
PAINT GREEN (-1573 2900);
DISPLAY INVISIBLE (-1573 2900);
FORCEADD UNIVERSAL_GND..1
(-1350 2500);
FORCEPROP 3 LASTPIN (-1350 2550) SIG_NAME GND\g
J 0
(-1340 2560);
DISPLAY 0.659574 (-1340 2560);
PAINT MONO (-1340 2560);
DISPLAY INVISIBLE (-1340 2560);
FORCEPROP 2 LAST ROOM IO_SLOT
J 1
(-1575 2575);
DISPLAY 0.744681 (-1575 2575);
FORCEPROP 2 LAST CDS_LIB pure_quanta_power
J 0
(-1350 2500);
PAINT MONO (-1350 2500);
DISPLAY INVISIBLE (-1350 2500);
FORCEPROP 1 LAST HDL_POWER GND
J 1
(-1325 2425);
DISPLAY 0.872340 (-1325 2425);
PAINT GREEN (-1325 2425);
DISPLAY INVISIBLE (-1325 2425);
FORCEPROP 1 LAST PATH I28
J 0
(-1275 2500);
DISPLAY 0.872340 (-1275 2500);
PAINT AQUA (-1275 2500);
DISPLAY INVISIBLE (-1275 2500);
FORCEADD TAP..1
R 2
(-1725 3300);
FORCEPROP 3 LASTPIN (-1675 3300) SIG_NAME P5E_CPU0_G3_TX_C_DN<12>
J 0
(-1665 3310);
DISPLAY 0.659574 (-1665 3310);
PAINT MONO (-1665 3310);
DISPLAY INVISIBLE (-1665 3310);
FORCEPROP 1 LASTPIN (-1675 3300) BN 12
J 2
(-1675 3300);
DISPLAY 0.680851 (-1675 3300);
PAINT GREEN (-1675 3300);
FORCEPROP 2 LAST CDS_LIB standard
J 0
(-1725 3300);
PAINT MONO (-1725 3300);
DISPLAY INVISIBLE (-1725 3300);
FORCEPROP 1 LAST BODY_TYPE PLUMBING
J 2
(-1725 3350);
DISPLAY 0.872340 (-1725 3350);
PAINT GREEN (-1725 3350);
DISPLAY INVISIBLE (-1725 3350);
FORCEPROP 1 LAST HDL_TAP TRUE
J 2
(-2050 3175);
DISPLAY 0.872340 (-2050 3175);
PAINT GREEN (-2050 3175);
DISPLAY INVISIBLE (-2050 3175);
FORCEPROP 1 LAST PATH I29
J 2
(-1723 3300);
DISPLAY 0.872340 (-1723 3300);
PAINT GREEN (-1723 3300);
DISPLAY INVISIBLE (-1723 3300);
FORCEADD Q_RES..2
(-4300 2250);
FORCEPROP 1 LAST LOCATION R31
J 0
(-4255 2375);
DISPLAY 0.978723 (-4255 2375);
FORCEPROP 2 LAST $SEC 1
J 0
(-4250 2475);
DISPLAY 0.680851 (-4250 2475);
PAINT MONO (-4250 2475);
DISPLAY INVISIBLE (-4250 2475);
FORCEPROP 2 LAST CDS_SEC 1
J 0
(-4250 2475);
DISPLAY 1.021277 (-4250 2475);
DISPLAY INVISIBLE (-4250 2475);
FORCEPROP 1 LASTPIN (-4300 2350) $PN 1
J 0
(-4295 2312);
DISPLAY 0.787234 (-4295 2312);
FORCEPROP 1 LASTPIN (-4300 2150) $PN 2
J 0
(-4295 2160);
DISPLAY 0.787234 (-4295 2160);
FORCEPROP 1 LAST WATTAGE 1/16W
J 0
(-4260 2225);
DISPLAY 0.787234 (-4260 2225);
FORCEPROP 1 LAST VALUE 4.7K
J 0
(-4255 2325);
DISPLAY 0.787234 (-4255 2325);
FORCEPROP 1 LAST PACK_TYPE 0402LF
J 0
(-4260 2075);
DISPLAY 0.787234 (-4260 2075);
FORCEPROP 1 LAST MATERIAL EMPTY
J 0
(-4260 2175);
DISPLAY 0.787234 (-4260 2175);
FORCEPROP 1 LAST TOLERANCE 1%
J 0
(-4255 2275);
DISPLAY 0.787234 (-4255 2275);
FORCEPROP 2 LAST CDS_LIB pure_quanta
J 0
(-4300 2250);
PAINT MONO (-4300 2250);
DISPLAY INVISIBLE (-4300 2250);
FORCEPROP 1 LAST PATH I3
J 0
(-4250 2425);
DISPLAY 0.978723 (-4250 2425);
PAINT WHITE (-4250 2425);
DISPLAY INVISIBLE (-4250 2425);
FORCEPROP 1 LAST PART_NUMBER CS24702FB06
J 0
(-4260 2125);
DISPLAY 0.787234 (-4260 2125);
DISPLAY INVISIBLE (-4260 2125);
FORCEADD TAP..1
R 2
(-1725 3150);
FORCEPROP 3 LASTPIN (-1675 3150) SIG_NAME P5E_CPU0_G3_TX_C_DN<13>
J 0
(-1665 3160);
DISPLAY 0.659574 (-1665 3160);
PAINT MONO (-1665 3160);
DISPLAY INVISIBLE (-1665 3160);
FORCEPROP 1 LASTPIN (-1675 3150) BN 13
J 2
(-1663 3158);
DISPLAY 0.680851 (-1663 3158);
PAINT GREEN (-1663 3158);
FORCEPROP 2 LAST CDS_LIB standard
J 0
(-1725 3150);
PAINT MONO (-1725 3150);
DISPLAY INVISIBLE (-1725 3150);
FORCEPROP 1 LAST BODY_TYPE PLUMBING
J 2
(-1725 3200);
DISPLAY 0.872340 (-1725 3200);
PAINT GREEN (-1725 3200);
DISPLAY INVISIBLE (-1725 3200);
FORCEPROP 1 LAST HDL_TAP TRUE
J 2
(-2050 3025);
DISPLAY 0.872340 (-2050 3025);
PAINT GREEN (-2050 3025);
DISPLAY INVISIBLE (-2050 3025);
FORCEPROP 1 LAST PATH I30
J 2
(-1723 3150);
DISPLAY 0.872340 (-1723 3150);
PAINT GREEN (-1723 3150);
DISPLAY INVISIBLE (-1723 3150);
FORCEADD TAP..1
R 2
(-1725 3450);
FORCEPROP 3 LASTPIN (-1675 3450) SIG_NAME P5E_CPU0_G3_TX_C_DN<11>
J 0
(-1665 3460);
DISPLAY 0.659574 (-1665 3460);
PAINT MONO (-1665 3460);
DISPLAY INVISIBLE (-1665 3460);
FORCEPROP 1 LASTPIN (-1675 3450) BN 11
J 2
(-1663 3458);
DISPLAY 0.680851 (-1663 3458);
PAINT GREEN (-1663 3458);
FORCEPROP 2 LAST CDS_LIB standard
J 0
(-1725 3450);
PAINT MONO (-1725 3450);
DISPLAY INVISIBLE (-1725 3450);
FORCEPROP 1 LAST BODY_TYPE PLUMBING
J 2
(-1725 3500);
DISPLAY 0.872340 (-1725 3500);
PAINT GREEN (-1725 3500);
DISPLAY INVISIBLE (-1725 3500);
FORCEPROP 1 LAST HDL_TAP TRUE
J 2
(-2050 3325);
DISPLAY 0.872340 (-2050 3325);
PAINT GREEN (-2050 3325);
DISPLAY INVISIBLE (-2050 3325);
FORCEPROP 1 LAST PATH I31
J 2
(-1723 3450);
DISPLAY 0.872340 (-1723 3450);
PAINT GREEN (-1723 3450);
DISPLAY INVISIBLE (-1723 3450);
FORCEADD TAP..1
R 2
(-1575 3200);
FORCEPROP 3 LASTPIN (-1525 3200) SIG_NAME P5E_CPU0_G3_TX_C_DP<13>
J 0
(-1515 3210);
DISPLAY 0.659574 (-1515 3210);
PAINT MONO (-1515 3210);
DISPLAY INVISIBLE (-1515 3210);
FORCEPROP 1 LASTPIN (-1525 3200) BN 13
J 2
(-1513 3208);
DISPLAY 0.680851 (-1513 3208);
PAINT GREEN (-1513 3208);
FORCEPROP 2 LAST CDS_LIB standard
J 0
(-1575 3200);
PAINT MONO (-1575 3200);
DISPLAY INVISIBLE (-1575 3200);
FORCEPROP 1 LAST BODY_TYPE PLUMBING
J 2
(-1575 3250);
DISPLAY 0.872340 (-1575 3250);
PAINT GREEN (-1575 3250);
DISPLAY INVISIBLE (-1575 3250);
FORCEPROP 1 LAST HDL_TAP TRUE
J 2
(-1900 3075);
DISPLAY 0.872340 (-1900 3075);
PAINT GREEN (-1900 3075);
DISPLAY INVISIBLE (-1900 3075);
FORCEPROP 1 LAST PATH I32
J 2
(-1573 3200);
DISPLAY 0.872340 (-1573 3200);
PAINT GREEN (-1573 3200);
DISPLAY INVISIBLE (-1573 3200);
FORCEADD TAP..1
R 2
(-1575 3500);
FORCEPROP 3 LASTPIN (-1525 3500) SIG_NAME P5E_CPU0_G3_TX_C_DP<11>
J 0
(-1515 3510);
DISPLAY 0.659574 (-1515 3510);
PAINT MONO (-1515 3510);
DISPLAY INVISIBLE (-1515 3510);
FORCEPROP 1 LASTPIN (-1525 3500) BN 11
J 2
(-1513 3508);
DISPLAY 0.680851 (-1513 3508);
PAINT GREEN (-1513 3508);
FORCEPROP 2 LAST CDS_LIB standard
J 0
(-1575 3500);
PAINT MONO (-1575 3500);
DISPLAY INVISIBLE (-1575 3500);
FORCEPROP 1 LAST BODY_TYPE PLUMBING
J 2
(-1575 3550);
DISPLAY 0.872340 (-1575 3550);
PAINT GREEN (-1575 3550);
DISPLAY INVISIBLE (-1575 3550);
FORCEPROP 1 LAST HDL_TAP TRUE
J 2
(-1900 3375);
DISPLAY 0.872340 (-1900 3375);
PAINT GREEN (-1900 3375);
DISPLAY INVISIBLE (-1900 3375);
FORCEPROP 1 LAST PATH I33
J 2
(-1573 3500);
DISPLAY 0.872340 (-1573 3500);
PAINT GREEN (-1573 3500);
DISPLAY INVISIBLE (-1573 3500);
FORCEADD TAP..1
R 2
(-1725 3900);
FORCEPROP 3 LASTPIN (-1675 3900) SIG_NAME P5E_CPU0_G3_TX_C_DN<8>
J 0
(-1665 3910);
DISPLAY 0.659574 (-1665 3910);
PAINT MONO (-1665 3910);
DISPLAY INVISIBLE (-1665 3910);
FORCEPROP 1 LASTPIN (-1675 3900) BN 8
J 2
(-1663 3908);
DISPLAY 0.680851 (-1663 3908);
PAINT GREEN (-1663 3908);
FORCEPROP 2 LAST CDS_LIB standard
J 0
(-1725 3900);
PAINT MONO (-1725 3900);
DISPLAY INVISIBLE (-1725 3900);
FORCEPROP 1 LAST BODY_TYPE PLUMBING
J 2
(-1725 3950);
DISPLAY 0.872340 (-1725 3950);
PAINT GREEN (-1725 3950);
DISPLAY INVISIBLE (-1725 3950);
FORCEPROP 1 LAST HDL_TAP TRUE
J 2
(-2050 3775);
DISPLAY 0.872340 (-2050 3775);
PAINT GREEN (-2050 3775);
DISPLAY INVISIBLE (-2050 3775);
FORCEPROP 1 LAST PATH I34
J 2
(-1723 3900);
DISPLAY 0.872340 (-1723 3900);
PAINT GREEN (-1723 3900);
DISPLAY INVISIBLE (-1723 3900);
FORCEADD TAP..1
R 2
(-1725 3600);
FORCEPROP 3 LASTPIN (-1675 3600) SIG_NAME P5E_CPU0_G3_TX_C_DN<10>
J 0
(-1665 3610);
DISPLAY 0.659574 (-1665 3610);
PAINT MONO (-1665 3610);
DISPLAY INVISIBLE (-1665 3610);
FORCEPROP 1 LASTPIN (-1675 3600) BN 10
J 2
(-1663 3608);
DISPLAY 0.680851 (-1663 3608);
PAINT GREEN (-1663 3608);
FORCEPROP 2 LAST CDS_LIB standard
J 0
(-1725 3600);
PAINT MONO (-1725 3600);
DISPLAY INVISIBLE (-1725 3600);
FORCEPROP 1 LAST BODY_TYPE PLUMBING
J 2
(-1725 3650);
DISPLAY 0.872340 (-1725 3650);
PAINT GREEN (-1725 3650);
DISPLAY INVISIBLE (-1725 3650);
FORCEPROP 1 LAST HDL_TAP TRUE
J 2
(-2050 3475);
DISPLAY 0.872340 (-2050 3475);
PAINT GREEN (-2050 3475);
DISPLAY INVISIBLE (-2050 3475);
FORCEPROP 1 LAST PATH I35
J 2
(-1723 3600);
DISPLAY 0.872340 (-1723 3600);
PAINT GREEN (-1723 3600);
DISPLAY INVISIBLE (-1723 3600);
FORCEADD TAP..1
R 2
(-1725 3750);
FORCEPROP 3 LASTPIN (-1675 3750) SIG_NAME P5E_CPU0_G3_TX_C_DN<9>
J 0
(-1665 3760);
DISPLAY 0.659574 (-1665 3760);
PAINT MONO (-1665 3760);
DISPLAY INVISIBLE (-1665 3760);
FORCEPROP 1 LASTPIN (-1675 3750) BN 9
J 2
(-1663 3758);
DISPLAY 0.680851 (-1663 3758);
PAINT GREEN (-1663 3758);
FORCEPROP 2 LAST CDS_LIB standard
J 0
(-1725 3750);
PAINT MONO (-1725 3750);
DISPLAY INVISIBLE (-1725 3750);
FORCEPROP 1 LAST BODY_TYPE PLUMBING
J 2
(-1725 3800);
DISPLAY 0.872340 (-1725 3800);
PAINT GREEN (-1725 3800);
DISPLAY INVISIBLE (-1725 3800);
FORCEPROP 1 LAST HDL_TAP TRUE
J 2
(-2050 3625);
DISPLAY 0.872340 (-2050 3625);
PAINT GREEN (-2050 3625);
DISPLAY INVISIBLE (-2050 3625);
FORCEPROP 1 LAST PATH I36
J 2
(-1723 3750);
DISPLAY 0.872340 (-1723 3750);
PAINT GREEN (-1723 3750);
DISPLAY INVISIBLE (-1723 3750);
FORCEADD TAP..1
R 2
(-1575 3650);
FORCEPROP 3 LASTPIN (-1525 3650) SIG_NAME P5E_CPU0_G3_TX_C_DP<10>
J 0
(-1515 3660);
DISPLAY 0.659574 (-1515 3660);
PAINT MONO (-1515 3660);
DISPLAY INVISIBLE (-1515 3660);
FORCEPROP 1 LASTPIN (-1525 3650) BN 10
J 2
(-1525 3650);
DISPLAY 0.680851 (-1525 3650);
PAINT GREEN (-1525 3650);
FORCEPROP 2 LAST CDS_LIB standard
J 0
(-1575 3650);
PAINT MONO (-1575 3650);
DISPLAY INVISIBLE (-1575 3650);
FORCEPROP 1 LAST BODY_TYPE PLUMBING
J 2
(-1575 3700);
DISPLAY 0.872340 (-1575 3700);
PAINT GREEN (-1575 3700);
DISPLAY INVISIBLE (-1575 3700);
FORCEPROP 1 LAST HDL_TAP TRUE
J 2
(-1900 3525);
DISPLAY 0.872340 (-1900 3525);
PAINT GREEN (-1900 3525);
DISPLAY INVISIBLE (-1900 3525);
FORCEPROP 1 LAST PATH I37
J 2
(-1573 3650);
DISPLAY 0.872340 (-1573 3650);
PAINT GREEN (-1573 3650);
DISPLAY INVISIBLE (-1573 3650);
FORCEADD TAP..1
R 2
(-1575 3800);
FORCEPROP 3 LASTPIN (-1525 3800) SIG_NAME P5E_CPU0_G3_TX_C_DP<9>
J 0
(-1515 3810);
DISPLAY 0.659574 (-1515 3810);
PAINT MONO (-1515 3810);
DISPLAY INVISIBLE (-1515 3810);
FORCEPROP 1 LASTPIN (-1525 3800) BN 9
J 2
(-1513 3808);
DISPLAY 0.680851 (-1513 3808);
PAINT GREEN (-1513 3808);
FORCEPROP 2 LAST CDS_LIB standard
J 0
(-1575 3800);
PAINT MONO (-1575 3800);
DISPLAY INVISIBLE (-1575 3800);
FORCEPROP 1 LAST BODY_TYPE PLUMBING
J 2
(-1575 3850);
DISPLAY 0.872340 (-1575 3850);
PAINT GREEN (-1575 3850);
DISPLAY INVISIBLE (-1575 3850);
FORCEPROP 1 LAST HDL_TAP TRUE
J 2
(-1900 3675);
DISPLAY 0.872340 (-1900 3675);
PAINT GREEN (-1900 3675);
DISPLAY INVISIBLE (-1900 3675);
FORCEPROP 1 LAST PATH I38
J 2
(-1573 3800);
DISPLAY 0.872340 (-1573 3800);
PAINT GREEN (-1573 3800);
DISPLAY INVISIBLE (-1573 3800);
FORCEADD TAP..1
R 2
(-1575 3950);
FORCEPROP 3 LASTPIN (-1525 3950) SIG_NAME P5E_CPU0_G3_TX_C_DP<8>
J 0
(-1515 3960);
DISPLAY 0.659574 (-1515 3960);
PAINT MONO (-1515 3960);
DISPLAY INVISIBLE (-1515 3960);
FORCEPROP 1 LASTPIN (-1525 3950) BN 8
J 2
(-1513 3958);
DISPLAY 0.680851 (-1513 3958);
PAINT GREEN (-1513 3958);
FORCEPROP 2 LAST CDS_LIB standard
J 0
(-1575 3950);
PAINT MONO (-1575 3950);
DISPLAY INVISIBLE (-1575 3950);
FORCEPROP 1 LAST BODY_TYPE PLUMBING
J 2
(-1575 4000);
DISPLAY 0.872340 (-1575 4000);
PAINT GREEN (-1575 4000);
DISPLAY INVISIBLE (-1575 4000);
FORCEPROP 1 LAST HDL_TAP TRUE
J 2
(-1900 3825);
DISPLAY 0.872340 (-1900 3825);
PAINT GREEN (-1900 3825);
DISPLAY INVISIBLE (-1900 3825);
FORCEPROP 1 LAST PATH I39
J 2
(-1573 3950);
DISPLAY 0.872340 (-1573 3950);
PAINT GREEN (-1573 3950);
DISPLAY INVISIBLE (-1573 3950);
FORCEADD UNIVERSAL_POWER..1
(-4300 2550);
FORCEPROP 3 LASTPIN (-4300 2500) SIG_NAME P3V3_OCP_SFF\g
J 0
(-4290 2510);
DISPLAY 0.659574 (-4290 2510);
PAINT MONO (-4290 2510);
DISPLAY INVISIBLE (-4290 2510);
FORCEPROP 1 LAST HDL_POWER P3V3_OCP_SFF
J 1
(-4300 2600);
DISPLAY 0.872340 (-4300 2600);
PAINT GREEN (-4300 2600);
FORCEPROP 2 LAST CDS_LIB pure_quanta_power
J 0
(-4300 2550);
PAINT MONO (-4300 2550);
DISPLAY INVISIBLE (-4300 2550);
FORCEPROP 1 LAST PATH I4
J 0
(-4250 2575);
DISPLAY 0.872340 (-4250 2575);
PAINT AQUA (-4250 2575);
DISPLAY INVISIBLE (-4250 2575);
FORCEADD UNIVERSAL_POWER..1
(-200 2125);
FORCEPROP 3 LASTPIN (-200 2075) SIG_NAME P3V3_OCP_SFF\g
J 0
(-190 2085);
DISPLAY 0.659574 (-190 2085);
PAINT MONO (-190 2085);
DISPLAY INVISIBLE (-190 2085);
FORCEPROP 1 LAST HDL_POWER P3V3_OCP_SFF
J 1
(-200 2175);
DISPLAY 0.872340 (-200 2175);
PAINT GREEN (-200 2175);
FORCEPROP 2 LAST CDS_LIB pure_quanta_power
J 0
(-200 2125);
PAINT MONO (-200 2125);
DISPLAY INVISIBLE (-200 2125);
FORCEPROP 1 LAST PATH I40
J 0
(-150 2150);
DISPLAY 0.872340 (-150 2150);
PAINT AQUA (-150 2150);
DISPLAY INVISIBLE (-150 2150);
FORCEADD OFFPAGE..1
(-3825 5850);
FORCEPROP 2 LAST $XR0 133 
J 0
(-4077 5850);
DISPLAY 0.638298 (-4077 5850);
PAINT MONO (-4077 5850);
FORCEPROP 2 LAST CDS_LIB standard
J 0
(-3825 5850);
PAINT MONO (-3825 5850);
DISPLAY INVISIBLE (-3825 5850);
FORCEPROP 1 LAST OFFPAGE TRUE
J 0
(-3500 5725);
DISPLAY 0.872340 (-3500 5725);
PAINT GREEN (-3500 5725);
DISPLAY INVISIBLE (-3500 5725);
FORCEPROP 1 LAST COMMENT_BODY TRUE
J 0
(-3700 5750);
DISPLAY 0.872340 (-3700 5750);
PAINT GREEN (-3700 5750);
DISPLAY INVISIBLE (-3700 5750);
FORCEPROP 2 LAST PATH I41
J 0
(-4075 5900);
DISPLAY 0.680851 (-4075 5900);
DISPLAY INVISIBLE (-4075 5900);
FORCEADD OFFPAGE..1
(-3825 5750);
FORCEPROP 2 LAST $XR2 132 
J 0
(-4317 5750);
DISPLAY 0.638298 (-4317 5750);
PAINT MONO (-4317 5750);
FORCEPROP 2 LAST $XR1 136 
J 0
(-4197 5750);
DISPLAY 0.638298 (-4197 5750);
PAINT MONO (-4197 5750);
FORCEPROP 2 LAST $XR0 131 
J 0
(-4077 5750);
DISPLAY 0.638298 (-4077 5750);
PAINT MONO (-4077 5750);
FORCEPROP 2 LAST CDS_LIB standard
J 0
(-3825 5750);
PAINT MONO (-3825 5750);
DISPLAY INVISIBLE (-3825 5750);
FORCEPROP 1 LAST OFFPAGE TRUE
J 0
(-3500 5625);
DISPLAY 0.872340 (-3500 5625);
PAINT GREEN (-3500 5625);
DISPLAY INVISIBLE (-3500 5625);
FORCEPROP 1 LAST COMMENT_BODY TRUE
J 0
(-3700 5650);
DISPLAY 0.872340 (-3700 5650);
PAINT GREEN (-3700 5650);
DISPLAY INVISIBLE (-3700 5650);
FORCEPROP 2 LAST PATH I42
J 0
(-4075 5800);
DISPLAY 0.680851 (-4075 5800);
DISPLAY INVISIBLE (-4075 5800);
FORCEADD OFFPAGE..1
(-3825 5900);
FORCEPROP 2 LAST $XR0 132 
J 0
(-4077 5900);
DISPLAY 0.638298 (-4077 5900);
PAINT MONO (-4077 5900);
FORCEPROP 2 LAST CDS_LIB standard
J 0
(-3825 5900);
PAINT MONO (-3825 5900);
DISPLAY INVISIBLE (-3825 5900);
FORCEPROP 1 LAST OFFPAGE TRUE
J 0
(-3500 5775);
DISPLAY 0.872340 (-3500 5775);
PAINT GREEN (-3500 5775);
DISPLAY INVISIBLE (-3500 5775);
FORCEPROP 1 LAST COMMENT_BODY TRUE
J 0
(-3700 5800);
DISPLAY 0.872340 (-3700 5800);
PAINT GREEN (-3700 5800);
DISPLAY INVISIBLE (-3700 5800);
FORCEPROP 2 LAST PATH I43
J 0
(-4075 5950);
DISPLAY 0.680851 (-4075 5950);
DISPLAY INVISIBLE (-4075 5950);
FORCEADD OFFPAGE..1
(-3825 6000);
FORCEPROP 2 LAST $XR0 132 
J 0
(-4077 6000);
DISPLAY 0.638298 (-4077 6000);
PAINT MONO (-4077 6000);
FORCEPROP 2 LAST CDS_LIB standard
J 0
(-3825 6000);
PAINT MONO (-3825 6000);
DISPLAY INVISIBLE (-3825 6000);
FORCEPROP 1 LAST OFFPAGE TRUE
J 0
(-3500 5875);
DISPLAY 0.872340 (-3500 5875);
PAINT GREEN (-3500 5875);
DISPLAY INVISIBLE (-3500 5875);
FORCEPROP 1 LAST COMMENT_BODY TRUE
J 0
(-3700 5900);
DISPLAY 0.872340 (-3700 5900);
PAINT GREEN (-3700 5900);
DISPLAY INVISIBLE (-3700 5900);
FORCEPROP 2 LAST PATH I44
J 0
(-4075 6050);
DISPLAY 0.680851 (-4075 6050);
DISPLAY INVISIBLE (-4075 6050);
FORCEADD OFFPAGE..1
(-3825 5950);
FORCEPROP 2 LAST $XR0 132 
J 0
(-4077 5950);
DISPLAY 0.638298 (-4077 5950);
PAINT MONO (-4077 5950);
FORCEPROP 2 LAST CDS_LIB standard
J 0
(-3825 5950);
PAINT MONO (-3825 5950);
DISPLAY INVISIBLE (-3825 5950);
FORCEPROP 1 LAST OFFPAGE TRUE
J 0
(-3500 5825);
DISPLAY 0.872340 (-3500 5825);
PAINT GREEN (-3500 5825);
DISPLAY INVISIBLE (-3500 5825);
FORCEPROP 1 LAST COMMENT_BODY TRUE
J 0
(-3700 5850);
DISPLAY 0.872340 (-3700 5850);
PAINT GREEN (-3700 5850);
DISPLAY INVISIBLE (-3700 5850);
FORCEPROP 2 LAST PATH I45
J 0
(-4075 6000);
DISPLAY 0.680851 (-4075 6000);
DISPLAY INVISIBLE (-4075 6000);
FORCEADD OFFPAGE..5
(-2775 4150);
FORCEPROP 2 LAST $XR1 143 
J 0
(-3150 4150);
DISPLAY 0.638298 (-3150 4150);
PAINT MONO (-3150 4150);
FORCEPROP 2 LAST $XR0 134 
J 0
(-3030 4150);
DISPLAY 0.638298 (-3030 4150);
PAINT MONO (-3030 4150);
FORCEPROP 2 LAST CDS_LIB standard
J 0
(-2775 4150);
PAINT MONO (-2775 4150);
DISPLAY INVISIBLE (-2775 4150);
FORCEPROP 1 LAST OFFPAGE TRUE
J 0
(-2450 4025);
DISPLAY 0.872340 (-2450 4025);
PAINT GREEN (-2450 4025);
DISPLAY INVISIBLE (-2450 4025);
FORCEPROP 1 LAST COMMENT_BODY TRUE
J 0
(-2675 4075);
DISPLAY 0.872340 (-2675 4075);
PAINT GREEN (-2675 4075);
DISPLAY INVISIBLE (-2675 4075);
FORCEPROP 2 LAST PATH I46
J 0
(-3050 4200);
DISPLAY 0.680851 (-3050 4200);
DISPLAY INVISIBLE (-3050 4200);
FORCEADD OFFPAGE..2
(-2875 4425);
FORCEPROP 2 LAST $XR2 132 
J 0
(-2476 4425);
DISPLAY 0.638298 (-2476 4425);
PAINT MONO (-2476 4425);
FORCEPROP 2 LAST $XR1 82 
J 0
(-2566 4425);
DISPLAY 0.638298 (-2566 4425);
PAINT MONO (-2566 4425);
FORCEPROP 2 LAST $XR0 131 
J 0
(-2686 4425);
DISPLAY 0.638298 (-2686 4425);
PAINT MONO (-2686 4425);
FORCEPROP 2 LAST CDS_LIB standard
J 0
(-2875 4425);
DISPLAY INVISIBLE (-2875 4425);
FORCEPROP 1 LAST OFFPAGE TRUE
J 0
(-2550 4300);
DISPLAY 0.872340 (-2550 4300);
PAINT GREEN (-2550 4300);
DISPLAY INVISIBLE (-2550 4300);
FORCEPROP 1 LAST COMMENT_BODY TRUE
J 0
(-2920 4330);
DISPLAY 0.872340 (-2920 4330);
PAINT GREEN (-2920 4330);
DISPLAY INVISIBLE (-2920 4330);
FORCEPROP 2 LAST PATH I47
J 0
(-2425 4475);
DISPLAY 0.680851 (-2425 4475);
DISPLAY INVISIBLE (-2425 4475);
FORCEADD OFFPAGE..2
(-2875 4625);
FORCEPROP 2 LAST $XR1 131 
J 0
(-2596 4625);
DISPLAY 0.638298 (-2596 4625);
PAINT MONO (-2596 4625);
FORCEPROP 2 LAST $XR0 82 
J 0
(-2686 4625);
DISPLAY 0.638298 (-2686 4625);
PAINT MONO (-2686 4625);
FORCEPROP 2 LAST CDS_LIB standard
J 0
(-2875 4625);
DISPLAY INVISIBLE (-2875 4625);
FORCEPROP 1 LAST OFFPAGE TRUE
J 0
(-2550 4500);
DISPLAY 0.872340 (-2550 4500);
PAINT GREEN (-2550 4500);
DISPLAY INVISIBLE (-2550 4500);
FORCEPROP 1 LAST COMMENT_BODY TRUE
J 0
(-2920 4530);
DISPLAY 0.872340 (-2920 4530);
PAINT GREEN (-2920 4530);
DISPLAY INVISIBLE (-2920 4530);
FORCEPROP 2 LAST PATH I48
J 0
(-2550 4675);
DISPLAY 0.680851 (-2550 4675);
DISPLAY INVISIBLE (-2550 4675);
FORCEADD OFFPAGE..2
(-2875 4725);
FORCEPROP 2 LAST $XR2 132 
J 0
(-2446 4725);
DISPLAY 0.638298 (-2446 4725);
PAINT MONO (-2446 4725);
FORCEPROP 2 LAST $XR1 131 
J 0
(-2566 4725);
DISPLAY 0.638298 (-2566 4725);
PAINT MONO (-2566 4725);
FORCEPROP 2 LAST $XR0 136 
J 0
(-2686 4725);
DISPLAY 0.638298 (-2686 4725);
PAINT MONO (-2686 4725);
FORCEPROP 2 LAST CDS_LIB standard
J 0
(-2875 4725);
DISPLAY INVISIBLE (-2875 4725);
FORCEPROP 1 LAST OFFPAGE TRUE
J 0
(-2550 4600);
DISPLAY 0.872340 (-2550 4600);
PAINT GREEN (-2550 4600);
DISPLAY INVISIBLE (-2550 4600);
FORCEPROP 1 LAST COMMENT_BODY TRUE
J 0
(-2920 4630);
DISPLAY 0.872340 (-2920 4630);
PAINT GREEN (-2920 4630);
DISPLAY INVISIBLE (-2920 4630);
FORCEPROP 2 LAST PATH I49
J 0
(-2425 4775);
DISPLAY 0.680851 (-2425 4775);
DISPLAY INVISIBLE (-2425 4775);
FORCEADD UNIVERSAL_GND..1
(-4650 4325);
FORCEPROP 3 LASTPIN (-4650 4375) SIG_NAME GND\g
J 0
(-4640 4385);
DISPLAY 0.659574 (-4640 4385);
PAINT MONO (-4640 4385);
DISPLAY INVISIBLE (-4640 4385);
FORCEPROP 2 LAST CDS_LIB pure_quanta_power
J 0
(-4650 4325);
DISPLAY INVISIBLE (-4650 4325);
FORCEPROP 1 LAST HDL_POWER GND
J 1
(-4625 4250);
DISPLAY 0.872340 (-4625 4250);
PAINT GREEN (-4625 4250);
DISPLAY INVISIBLE (-4625 4250);
FORCEPROP 1 LAST PATH I5
J 0
(-4575 4325);
DISPLAY 0.872340 (-4575 4325);
PAINT AQUA (-4575 4325);
DISPLAY INVISIBLE (-4575 4325);
FORCEADD OFFPAGE..1
(-2775 5600);
FORCEPROP 2 LAST $XR0 28 
J 0
(-3026 5600);
DISPLAY 0.638298 (-3026 5600);
PAINT MONO (-3026 5600);
FORCEPROP 2 LAST CDS_LIB standard
J 0
(-2775 5600);
PAINT MONO (-2775 5600);
DISPLAY INVISIBLE (-2775 5600);
FORCEPROP 1 LAST OFFPAGE TRUE
J 0
(-2450 5475);
DISPLAY 0.872340 (-2450 5475);
PAINT GREEN (-2450 5475);
DISPLAY INVISIBLE (-2450 5475);
FORCEPROP 1 LAST COMMENT_BODY TRUE
J 0
(-2650 5500);
DISPLAY 0.872340 (-2650 5500);
PAINT GREEN (-2650 5500);
DISPLAY INVISIBLE (-2650 5500);
FORCEPROP 2 LAST PATH I50
J 0
(-3025 5650);
DISPLAY 0.680851 (-3025 5650);
DISPLAY INVISIBLE (-3025 5650);
FORCEADD OFFPAGE..1
(-2775 5525);
FORCEPROP 2 LAST $XR0 65 
J 0
(-3026 5525);
DISPLAY 0.638298 (-3026 5525);
PAINT MONO (-3026 5525);
FORCEPROP 2 LAST CDS_LIB standard
J 0
(-2775 5525);
DISPLAY INVISIBLE (-2775 5525);
FORCEPROP 1 LAST OFFPAGE TRUE
J 0
(-2450 5400);
DISPLAY 0.872340 (-2450 5400);
PAINT GREEN (-2450 5400);
DISPLAY INVISIBLE (-2450 5400);
FORCEPROP 1 LAST COMMENT_BODY TRUE
J 0
(-2650 5425);
DISPLAY 0.872340 (-2650 5425);
PAINT GREEN (-2650 5425);
DISPLAY INVISIBLE (-2650 5425);
FORCEPROP 2 LAST PATH I51
J 0
(-3025 5575);
DISPLAY 0.680851 (-3025 5575);
DISPLAY INVISIBLE (-3025 5575);
FORCEADD OFFPAGE..1
(-2775 5475);
FORCEPROP 2 LAST $XR0 65 
J 0
(-3026 5475);
DISPLAY 0.638298 (-3026 5475);
PAINT MONO (-3026 5475);
FORCEPROP 2 LAST CDS_LIB standard
J 0
(-2775 5475);
DISPLAY INVISIBLE (-2775 5475);
FORCEPROP 1 LAST OFFPAGE TRUE
J 0
(-2450 5350);
DISPLAY 0.872340 (-2450 5350);
PAINT GREEN (-2450 5350);
DISPLAY INVISIBLE (-2450 5350);
FORCEPROP 1 LAST COMMENT_BODY TRUE
J 0
(-2650 5375);
DISPLAY 0.872340 (-2650 5375);
PAINT GREEN (-2650 5375);
DISPLAY INVISIBLE (-2650 5375);
FORCEPROP 2 LAST PATH I52
J 0
(-3025 5525);
DISPLAY 0.680851 (-3025 5525);
DISPLAY INVISIBLE (-3025 5525);
FORCEADD OFFPAGE..1
(-2775 5650);
FORCEPROP 2 LAST $XR0 28 
J 0
(-3026 5650);
DISPLAY 0.638298 (-3026 5650);
PAINT MONO (-3026 5650);
FORCEPROP 2 LAST CDS_LIB standard
J 0
(-2775 5650);
PAINT MONO (-2775 5650);
DISPLAY INVISIBLE (-2775 5650);
FORCEPROP 1 LAST OFFPAGE TRUE
J 0
(-2450 5525);
DISPLAY 0.872340 (-2450 5525);
PAINT GREEN (-2450 5525);
DISPLAY INVISIBLE (-2450 5525);
FORCEPROP 1 LAST COMMENT_BODY TRUE
J 0
(-2650 5550);
DISPLAY 0.872340 (-2650 5550);
PAINT GREEN (-2650 5550);
DISPLAY INVISIBLE (-2650 5550);
FORCEPROP 2 LAST PATH I53
J 0
(-3025 5700);
DISPLAY 0.680851 (-3025 5700);
DISPLAY INVISIBLE (-3025 5700);
FORCEADD Q_RES..1
(-2875 5750);
FORCEPROP 1 LAST LOCATION R1671
J 0
(-3125 5750);
DISPLAY 0.787234 (-3125 5750);
FORCEPROP 2 LAST $SEC 1
J 0
(-2925 5950);
DISPLAY 0.680851 (-2925 5950);
PAINT MONO (-2925 5950);
DISPLAY INVISIBLE (-2925 5950);
FORCEPROP 2 LAST CDS_SEC 1
J 0
(-2925 5950);
DISPLAY 1.021277 (-2925 5950);
DISPLAY INVISIBLE (-2925 5950);
FORCEPROP 1 LASTPIN (-2975 5750) $PN 1
J 0
(-2963 5762);
DISPLAY 0.787234 (-2963 5762);
FORCEPROP 1 LASTPIN (-2775 5750) $PN 2
J 0
(-2813 5762);
DISPLAY 0.787234 (-2813 5762);
FORCEPROP 1 LAST PACK_TYPE 0402LF
J 0
(-2600 5750);
DISPLAY 0.638298 (-2600 5750);
FORCEPROP 1 LAST TOLERANCE 5%
J 0
(-2675 5750);
DISPLAY 0.638298 (-2675 5750);
FORCEPROP 1 LAST VALUE 0
J 2
(-2700 5750);
DISPLAY 0.638298 (-2700 5750);
FORCEPROP 2 LAST CDS_LIB pure_quanta
J 0
(-2875 5750);
PAINT MONO (-2875 5750);
DISPLAY INVISIBLE (-2875 5750);
FORCEPROP 1 LAST MATERIAL CHIP
J 0
(-3000 5875);
DISPLAY 0.638298 (-3000 5875);
DISPLAY INVISIBLE (-3000 5875);
FORCEPROP 1 LAST WATTAGE 1/16W
J 2
(-2700 5875);
DISPLAY 0.638298 (-2700 5875);
DISPLAY INVISIBLE (-2700 5875);
FORCEPROP 1 LAST PATH I54
J 0
(-2925 5900);
DISPLAY 0.978723 (-2925 5900);
PAINT WHITE (-2925 5900);
DISPLAY INVISIBLE (-2925 5900);
FORCEPROP 1 LAST PART_NUMBER CS00002JB13
J 0
(-3000 5825);
DISPLAY 0.638298 (-3000 5825);
DISPLAY INVISIBLE (-3000 5825);
FORCEADD Q_RES..1
(-2875 5900);
FORCEPROP 1 LAST LOCATION R41
J 0
(-3100 5900);
DISPLAY 0.787234 (-3100 5900);
FORCEPROP 2 LAST $SEC 1
J 0
(-2925 6100);
DISPLAY 0.680851 (-2925 6100);
PAINT MONO (-2925 6100);
DISPLAY INVISIBLE (-2925 6100);
FORCEPROP 2 LAST CDS_SEC 1
J 0
(-2925 6100);
DISPLAY 1.021277 (-2925 6100);
DISPLAY INVISIBLE (-2925 6100);
FORCEPROP 1 LASTPIN (-2975 5900) $PN 1
J 0
(-2963 5912);
DISPLAY 0.787234 (-2963 5912);
FORCEPROP 1 LASTPIN (-2775 5900) $PN 2
J 0
(-2813 5912);
DISPLAY 0.787234 (-2813 5912);
FORCEPROP 1 LAST TOLERANCE 5%
J 0
(-2675 5900);
DISPLAY 0.638298 (-2675 5900);
FORCEPROP 1 LAST VALUE 0
J 2
(-2700 5900);
DISPLAY 0.638298 (-2700 5900);
FORCEPROP 1 LAST PACK_TYPE 0402LF
J 0
(-2600 5900);
DISPLAY 0.638298 (-2600 5900);
FORCEPROP 1 LAST WATTAGE 1/16W
J 2
(-2700 6025);
DISPLAY 0.638298 (-2700 6025);
DISPLAY INVISIBLE (-2700 6025);
FORCEPROP 1 LAST MATERIAL CHIP
J 0
(-3000 6025);
DISPLAY 0.638298 (-3000 6025);
DISPLAY INVISIBLE (-3000 6025);
FORCEPROP 2 LAST CDS_LIB pure_quanta
J 0
(-2875 5900);
PAINT MONO (-2875 5900);
DISPLAY INVISIBLE (-2875 5900);
FORCEPROP 1 LAST PATH I55
J 0
(-2925 6050);
DISPLAY 0.978723 (-2925 6050);
PAINT WHITE (-2925 6050);
DISPLAY INVISIBLE (-2925 6050);
FORCEPROP 1 LAST PART_NUMBER CS00002JB13
J 0
(-3000 5975);
DISPLAY 0.638298 (-3000 5975);
DISPLAY INVISIBLE (-3000 5975);
FORCEADD Q_RES..1
(-2875 5950);
FORCEPROP 1 LAST LOCATION R40
J 0
(-3100 5950);
DISPLAY 0.787234 (-3100 5950);
FORCEPROP 2 LAST $SEC 1
J 0
(-2925 6150);
DISPLAY 0.680851 (-2925 6150);
PAINT MONO (-2925 6150);
DISPLAY INVISIBLE (-2925 6150);
FORCEPROP 2 LAST CDS_SEC 1
J 0
(-2925 6150);
DISPLAY 1.021277 (-2925 6150);
DISPLAY INVISIBLE (-2925 6150);
FORCEPROP 1 LASTPIN (-2975 5950) $PN 1
J 0
(-2963 5962);
DISPLAY 0.787234 (-2963 5962);
FORCEPROP 1 LASTPIN (-2775 5950) $PN 2
J 0
(-2813 5962);
DISPLAY 0.787234 (-2813 5962);
FORCEPROP 1 LAST TOLERANCE 5%
J 0
(-2675 5950);
DISPLAY 0.638298 (-2675 5950);
FORCEPROP 1 LAST VALUE 0
J 2
(-2700 5950);
DISPLAY 0.638298 (-2700 5950);
FORCEPROP 1 LAST PACK_TYPE 0402LF
J 0
(-2600 5950);
DISPLAY 0.638298 (-2600 5950);
FORCEPROP 2 LAST CDS_LIB pure_quanta
J 0
(-2875 5950);
PAINT MONO (-2875 5950);
DISPLAY INVISIBLE (-2875 5950);
FORCEPROP 1 LAST MATERIAL CHIP
J 0
(-3000 6075);
DISPLAY 0.638298 (-3000 6075);
DISPLAY INVISIBLE (-3000 6075);
FORCEPROP 1 LAST WATTAGE 1/16W
J 2
(-2700 6075);
DISPLAY 0.638298 (-2700 6075);
DISPLAY INVISIBLE (-2700 6075);
FORCEPROP 1 LAST PATH I56
J 0
(-2925 6100);
DISPLAY 0.978723 (-2925 6100);
PAINT WHITE (-2925 6100);
DISPLAY INVISIBLE (-2925 6100);
FORCEPROP 1 LAST PART_NUMBER CS00002JB13
J 0
(-3000 6025);
DISPLAY 0.638298 (-3000 6025);
DISPLAY INVISIBLE (-3000 6025);
FORCEADD Q_RES..1
(-2875 6000);
FORCEPROP 1 LAST LOCATION R39
J 0
(-3100 6000);
DISPLAY 0.787234 (-3100 6000);
FORCEPROP 2 LAST $SEC 1
J 0
(-2925 6200);
DISPLAY 0.680851 (-2925 6200);
PAINT MONO (-2925 6200);
DISPLAY INVISIBLE (-2925 6200);
FORCEPROP 2 LAST CDS_SEC 1
J 0
(-2925 6200);
DISPLAY 1.021277 (-2925 6200);
DISPLAY INVISIBLE (-2925 6200);
FORCEPROP 1 LASTPIN (-2975 6000) $PN 1
J 0
(-2963 6012);
DISPLAY 0.787234 (-2963 6012);
FORCEPROP 1 LASTPIN (-2775 6000) $PN 2
J 0
(-2813 6012);
DISPLAY 0.787234 (-2813 6012);
FORCEPROP 1 LAST VALUE 0
J 2
(-2700 6000);
DISPLAY 0.638298 (-2700 6000);
FORCEPROP 1 LAST TOLERANCE 5%
J 0
(-2675 6000);
DISPLAY 0.638298 (-2675 6000);
FORCEPROP 1 LAST MATERIAL CHIP
J 0
(-3000 6125);
DISPLAY 0.638298 (-3000 6125);
FORCEPROP 1 LAST PACK_TYPE 0402LF
J 0
(-2600 6000);
DISPLAY 0.638298 (-2600 6000);
FORCEPROP 1 LAST WATTAGE 1/16W
J 2
(-2700 6125);
DISPLAY 0.638298 (-2700 6125);
FORCEPROP 2 LAST CDS_LIB pure_quanta
J 0
(-2875 6000);
PAINT MONO (-2875 6000);
DISPLAY INVISIBLE (-2875 6000);
FORCEPROP 1 LAST PATH I57
J 0
(-2925 6150);
DISPLAY 0.978723 (-2925 6150);
PAINT WHITE (-2925 6150);
DISPLAY INVISIBLE (-2925 6150);
FORCEPROP 1 LAST PART_NUMBER CS00002JB13
J 0
(-3000 6075);
DISPLAY 0.638298 (-3000 6075);
DISPLAY INVISIBLE (-3000 6075);
FORCEADD UNIVERSAL_POWER..1
(-2250 6175);
FORCEPROP 3 LASTPIN (-2250 6125) SIG_NAME P3V3_OCP_SFF\g
J 0
(-2240 6135);
DISPLAY 0.659574 (-2240 6135);
PAINT MONO (-2240 6135);
DISPLAY INVISIBLE (-2240 6135);
FORCEPROP 1 LAST HDL_POWER P3V3_OCP_SFF
J 1
(-2250 6225);
DISPLAY 0.872340 (-2250 6225);
PAINT GREEN (-2250 6225);
FORCEPROP 2 LAST CDS_LIB pure_quanta_power
J 0
(-2250 6175);
DISPLAY INVISIBLE (-2250 6175);
FORCEPROP 1 LAST PATH I58
J 0
(-2200 6200);
DISPLAY 0.872340 (-2200 6200);
PAINT AQUA (-2200 6200);
DISPLAY INVISIBLE (-2200 6200);
FORCEADD Q_RES..1
(-2875 7050);
FORCEPROP 1 LAST LOCATION R38
J 0
(-3100 7050);
DISPLAY 0.638298 (-3100 7050);
FORCEPROP 2 LAST $SEC 1
J 0
(-2925 7250);
DISPLAY 0.680851 (-2925 7250);
PAINT MONO (-2925 7250);
DISPLAY INVISIBLE (-2925 7250);
FORCEPROP 2 LAST CDS_SEC 1
J 0
(-2925 7250);
DISPLAY 1.021277 (-2925 7250);
DISPLAY INVISIBLE (-2925 7250);
FORCEPROP 1 LASTPIN (-2975 7050) $PN 1
J 0
(-2963 7062);
DISPLAY 0.787234 (-2963 7062);
FORCEPROP 1 LASTPIN (-2775 7050) $PN 2
J 0
(-2813 7062);
DISPLAY 0.787234 (-2813 7062);
FORCEPROP 1 LAST TOLERANCE 5%
J 0
(-2675 7050);
DISPLAY 0.638298 (-2675 7050);
FORCEPROP 1 LAST VALUE 0
J 2
(-2700 7050);
DISPLAY 0.638298 (-2700 7050);
FORCEPROP 1 LAST PACK_TYPE 0402LF
J 0
(-2600 7050);
DISPLAY 0.638298 (-2600 7050);
FORCEPROP 2 LAST CDS_LIB pure_quanta
J 0
(-2875 7050);
PAINT MONO (-2875 7050);
DISPLAY INVISIBLE (-2875 7050);
FORCEPROP 1 LAST WATTAGE 1/16W
J 2
(-2700 7175);
DISPLAY 0.638298 (-2700 7175);
DISPLAY INVISIBLE (-2700 7175);
FORCEPROP 1 LAST MATERIAL CHIP
J 0
(-3000 7175);
DISPLAY 0.638298 (-3000 7175);
DISPLAY INVISIBLE (-3000 7175);
FORCEPROP 1 LAST PATH I59
J 0
(-2925 7200);
DISPLAY 0.978723 (-2925 7200);
PAINT WHITE (-2925 7200);
DISPLAY INVISIBLE (-2925 7200);
FORCEPROP 1 LAST PART_NUMBER CS00002JB13
J 0
(-3000 7125);
DISPLAY 0.638298 (-3000 7125);
DISPLAY INVISIBLE (-3000 7125);
FORCEADD Q_RES..1
(-4225 4425);
FORCEPROP 1 LAST LOCATION R3132
J 0
(-4500 4425);
DISPLAY 0.787234 (-4500 4425);
FORCEPROP 0 LAST $SEC 1
J 0
(-4025 4550);
DISPLAY 0.680851 (-4025 4550);
PAINT MONO (-4025 4550);
DISPLAY INVISIBLE (-4025 4550);
FORCEPROP 0 LAST CDS_SEC 1
J 0
(-4025 4550);
DISPLAY 1.021277 (-4025 4550);
DISPLAY INVISIBLE (-4025 4550);
FORCEPROP 1 LASTPIN (-4325 4425) $PN 1
J 0
(-4313 4437);
DISPLAY 0.787234 (-4313 4437);
PAINT MONO (-4313 4437);
FORCEPROP 1 LASTPIN (-4125 4425) $PN 2
J 0
(-4163 4437);
DISPLAY 0.787234 (-4163 4437);
PAINT MONO (-4163 4437);
FORCEPROP 1 LAST WATTAGE 1/16W
J 2
(-4025 4525);
DISPLAY 0.510638 (-4025 4525);
FORCEPROP 1 LAST VALUE 100K
J 2
(-4025 4425);
DISPLAY 0.510638 (-4025 4425);
FORCEPROP 1 LAST MATERIAL CHIP
J 0
(-3900 4425);
DISPLAY 0.510638 (-3900 4425);
FORCEPROP 1 LAST TOLERANCE 1%
J 0
(-4000 4425);
DISPLAY 0.510638 (-4000 4425);
FORCEPROP 1 LAST PACK_TYPE 0402LF
J 0
(-4400 4525);
DISPLAY 0.510638 (-4400 4525);
FORCEPROP 2 LAST CDS_LIB pure_quanta
J 0
(-4225 4425);
DISPLAY INVISIBLE (-4225 4425);
FORCEPROP 1 LAST PATH I6
J 0
(-4275 4575);
DISPLAY 0.978723 (-4275 4575);
PAINT WHITE (-4275 4575);
DISPLAY INVISIBLE (-4275 4575);
FORCEPROP 1 LAST PART_NUMBER CS41002FB09
J 0
(-4400 4475);
DISPLAY 0.510638 (-4400 4475);
DISPLAY INVISIBLE (-4400 4475);
FORCEADD OFFPAGE..1
(-2325 6550);
FORCEPROP 2 LAST $XR0 28 
J 0
(-2576 6550);
DISPLAY 0.638298 (-2576 6550);
PAINT MONO (-2576 6550);
FORCEPROP 2 LAST CDS_LIB standard
J 0
(-2325 6550);
PAINT MONO (-2325 6550);
DISPLAY INVISIBLE (-2325 6550);
FORCEPROP 1 LAST OFFPAGE TRUE
J 0
(-2000 6425);
DISPLAY 0.872340 (-2000 6425);
PAINT GREEN (-2000 6425);
DISPLAY INVISIBLE (-2000 6425);
FORCEPROP 1 LAST COMMENT_BODY TRUE
J 0
(-2200 6450);
DISPLAY 0.872340 (-2200 6450);
PAINT GREEN (-2200 6450);
DISPLAY INVISIBLE (-2200 6450);
FORCEPROP 2 LAST PATH I60
J 0
(-2575 6600);
DISPLAY 0.680851 (-2575 6600);
DISPLAY INVISIBLE (-2575 6600);
FORCEADD OFFPAGE..1
(-2325 6600);
FORCEPROP 2 LAST $XR0 28 
J 0
(-2576 6600);
DISPLAY 0.638298 (-2576 6600);
PAINT MONO (-2576 6600);
FORCEPROP 2 LAST CDS_LIB standard
J 0
(-2325 6600);
PAINT MONO (-2325 6600);
DISPLAY INVISIBLE (-2325 6600);
FORCEPROP 1 LAST OFFPAGE TRUE
J 0
(-2000 6475);
DISPLAY 0.872340 (-2000 6475);
PAINT GREEN (-2000 6475);
DISPLAY INVISIBLE (-2000 6475);
FORCEPROP 1 LAST COMMENT_BODY TRUE
J 0
(-2200 6500);
DISPLAY 0.872340 (-2200 6500);
PAINT GREEN (-2200 6500);
DISPLAY INVISIBLE (-2200 6500);
FORCEPROP 2 LAST PATH I61
J 0
(-2575 6650);
DISPLAY 0.680851 (-2575 6650);
DISPLAY INVISIBLE (-2575 6650);
FORCEADD OFFPAGE..5
(-2325 6450);
FORCEPROP 2 LAST $XR0 132 
J 0
(-2580 6450);
DISPLAY 0.638298 (-2580 6450);
PAINT MONO (-2580 6450);
FORCEPROP 2 LAST CDS_LIB standard
J 0
(-2325 6450);
PAINT MONO (-2325 6450);
DISPLAY INVISIBLE (-2325 6450);
FORCEPROP 1 LAST OFFPAGE TRUE
J 0
(-2000 6325);
DISPLAY 0.872340 (-2000 6325);
PAINT GREEN (-2000 6325);
DISPLAY INVISIBLE (-2000 6325);
FORCEPROP 1 LAST COMMENT_BODY TRUE
J 0
(-2225 6375);
DISPLAY 0.872340 (-2225 6375);
PAINT GREEN (-2225 6375);
DISPLAY INVISIBLE (-2225 6375);
FORCEPROP 2 LAST PATH I62
J 0
(-2600 6500);
DISPLAY 0.680851 (-2600 6500);
DISPLAY INVISIBLE (-2600 6500);
FORCEADD OFFPAGE..5
(-2325 6700);
FORCEPROP 2 LAST $XR0 132 
J 0
(-2580 6700);
DISPLAY 0.638298 (-2580 6700);
PAINT MONO (-2580 6700);
FORCEPROP 2 LAST CDS_LIB standard
J 0
(-2325 6700);
PAINT MONO (-2325 6700);
DISPLAY INVISIBLE (-2325 6700);
FORCEPROP 1 LAST OFFPAGE TRUE
J 0
(-2000 6575);
DISPLAY 0.872340 (-2000 6575);
PAINT GREEN (-2000 6575);
DISPLAY INVISIBLE (-2000 6575);
FORCEPROP 1 LAST COMMENT_BODY TRUE
J 0
(-2225 6625);
DISPLAY 0.872340 (-2225 6625);
PAINT GREEN (-2225 6625);
DISPLAY INVISIBLE (-2225 6625);
FORCEPROP 2 LAST PATH I63
J 0
(-2600 6750);
DISPLAY 0.680851 (-2600 6750);
DISPLAY INVISIBLE (-2600 6750);
FORCEADD OFFPAGE..5
(-2325 6750);
FORCEPROP 2 LAST $XR0 132 
J 0
(-2580 6750);
DISPLAY 0.638298 (-2580 6750);
PAINT MONO (-2580 6750);
FORCEPROP 2 LAST CDS_LIB standard
J 0
(-2325 6750);
PAINT MONO (-2325 6750);
DISPLAY INVISIBLE (-2325 6750);
FORCEPROP 1 LAST OFFPAGE TRUE
J 0
(-2000 6625);
DISPLAY 0.872340 (-2000 6625);
PAINT GREEN (-2000 6625);
DISPLAY INVISIBLE (-2000 6625);
FORCEPROP 1 LAST COMMENT_BODY TRUE
J 0
(-2225 6675);
DISPLAY 0.872340 (-2225 6675);
PAINT GREEN (-2225 6675);
DISPLAY INVISIBLE (-2225 6675);
FORCEPROP 2 LAST PATH I64
J 0
(-2600 6800);
DISPLAY 0.680851 (-2600 6800);
DISPLAY INVISIBLE (-2600 6800);
FORCEADD OFFPAGE..1
(-2325 6800);
FORCEPROP 2 LAST $XR0 131 
J 0
(-2607 6800);
DISPLAY 0.638298 (-2607 6800);
PAINT MONO (-2607 6800);
FORCEPROP 2 LAST CDS_LIB standard
J 0
(-2325 6800);
PAINT MONO (-2325 6800);
DISPLAY INVISIBLE (-2325 6800);
FORCEPROP 1 LAST OFFPAGE TRUE
J 0
(-2000 6675);
DISPLAY 0.872340 (-2000 6675);
PAINT GREEN (-2000 6675);
DISPLAY INVISIBLE (-2000 6675);
FORCEPROP 1 LAST COMMENT_BODY TRUE
J 0
(-2200 6700);
DISPLAY 0.872340 (-2200 6700);
PAINT GREEN (-2200 6700);
DISPLAY INVISIBLE (-2200 6700);
FORCEPROP 2 LAST PATH I65
J 0
(-2600 6850);
DISPLAY 0.680851 (-2600 6850);
DISPLAY INVISIBLE (-2600 6850);
FORCEADD OFFPAGE..5
(-2325 6850);
FORCEPROP 2 LAST $XR1 80 
J 0
(-2670 6850);
DISPLAY 0.638298 (-2670 6850);
PAINT MONO (-2670 6850);
FORCEPROP 2 LAST $XR0 131 
J 0
(-2580 6850);
DISPLAY 0.638298 (-2580 6850);
PAINT MONO (-2580 6850);
FORCEPROP 2 LAST CDS_LIB standard
J 0
(-2325 6850);
PAINT MONO (-2325 6850);
DISPLAY INVISIBLE (-2325 6850);
FORCEPROP 1 LAST OFFPAGE TRUE
J 0
(-2000 6725);
DISPLAY 0.872340 (-2000 6725);
PAINT GREEN (-2000 6725);
DISPLAY INVISIBLE (-2000 6725);
FORCEPROP 1 LAST COMMENT_BODY TRUE
J 0
(-2225 6775);
DISPLAY 0.872340 (-2225 6775);
PAINT GREEN (-2225 6775);
DISPLAY INVISIBLE (-2225 6775);
FORCEPROP 2 LAST PATH I66
J 0
(-2600 6900);
DISPLAY 0.680851 (-2600 6900);
DISPLAY INVISIBLE (-2600 6900);
FORCEADD OFFPAGE..1
(-2325 6900);
FORCEPROP 2 LAST $XR1 131 
J 0
(-2696 6900);
DISPLAY 0.638298 (-2696 6900);
PAINT MONO (-2696 6900);
FORCEPROP 2 LAST $XR0 80 
J 0
(-2576 6900);
DISPLAY 0.638298 (-2576 6900);
PAINT MONO (-2576 6900);
FORCEPROP 2 LAST CDS_LIB standard
J 0
(-2325 6900);
PAINT MONO (-2325 6900);
DISPLAY INVISIBLE (-2325 6900);
FORCEPROP 1 LAST OFFPAGE TRUE
J 0
(-2000 6775);
DISPLAY 0.872340 (-2000 6775);
PAINT GREEN (-2000 6775);
DISPLAY INVISIBLE (-2000 6775);
FORCEPROP 1 LAST COMMENT_BODY TRUE
J 0
(-2200 6800);
DISPLAY 0.872340 (-2200 6800);
PAINT GREEN (-2200 6800);
DISPLAY INVISIBLE (-2200 6800);
FORCEPROP 2 LAST PATH I67
J 0
(-2575 6950);
DISPLAY 0.680851 (-2575 6950);
DISPLAY INVISIBLE (-2575 6950);
FORCEADD OFFPAGE..1
(-2325 7000);
FORCEPROP 2 LAST $XR1 131 
J 0
(-2696 7000);
DISPLAY 0.638298 (-2696 7000);
PAINT MONO (-2696 7000);
FORCEPROP 2 LAST $XR0 80 
J 0
(-2576 7000);
DISPLAY 0.638298 (-2576 7000);
PAINT MONO (-2576 7000);
FORCEPROP 2 LAST CDS_LIB standard
J 0
(-2325 7000);
PAINT MONO (-2325 7000);
DISPLAY INVISIBLE (-2325 7000);
FORCEPROP 1 LAST OFFPAGE TRUE
J 0
(-2000 6875);
DISPLAY 0.872340 (-2000 6875);
PAINT GREEN (-2000 6875);
DISPLAY INVISIBLE (-2000 6875);
FORCEPROP 1 LAST COMMENT_BODY TRUE
J 0
(-2200 6900);
DISPLAY 0.872340 (-2200 6900);
PAINT GREEN (-2200 6900);
DISPLAY INVISIBLE (-2200 6900);
FORCEPROP 2 LAST PATH I68
J 0
(-2575 7050);
DISPLAY 0.680851 (-2575 7050);
DISPLAY INVISIBLE (-2575 7050);
FORCEADD OFFPAGE..1
(-2325 6950);
FORCEPROP 2 LAST $XR1 131 
J 0
(-2696 6950);
DISPLAY 0.638298 (-2696 6950);
PAINT MONO (-2696 6950);
FORCEPROP 2 LAST $XR0 80 
J 0
(-2576 6950);
DISPLAY 0.638298 (-2576 6950);
PAINT MONO (-2576 6950);
FORCEPROP 2 LAST CDS_LIB standard
J 0
(-2325 6950);
PAINT MONO (-2325 6950);
DISPLAY INVISIBLE (-2325 6950);
FORCEPROP 1 LAST OFFPAGE TRUE
J 0
(-2000 6825);
DISPLAY 0.872340 (-2000 6825);
PAINT GREEN (-2000 6825);
DISPLAY INVISIBLE (-2000 6825);
FORCEPROP 1 LAST COMMENT_BODY TRUE
J 0
(-2200 6850);
DISPLAY 0.872340 (-2200 6850);
PAINT GREEN (-2200 6850);
DISPLAY INVISIBLE (-2200 6850);
FORCEPROP 2 LAST PATH I69
J 0
(-2575 7000);
DISPLAY 0.680851 (-2575 7000);
DISPLAY INVISIBLE (-2575 7000);
FORCEADD Q_RES..1
(-4225 4625);
FORCEPROP 1 LAST LOCATION R1930
J 0
(-4500 4625);
DISPLAY 0.787234 (-4500 4625);
FORCEPROP 0 LAST $SEC 1
J 0
(-4500 4675);
DISPLAY 0.680851 (-4500 4675);
PAINT MONO (-4500 4675);
DISPLAY INVISIBLE (-4500 4675);
FORCEPROP 0 LAST CDS_SEC 1
J 0
(-4500 4675);
DISPLAY 1.021277 (-4500 4675);
DISPLAY INVISIBLE (-4500 4675);
FORCEPROP 1 LASTPIN (-4325 4625) $PN 1
J 0
(-4313 4637);
DISPLAY 0.787234 (-4313 4637);
PAINT MONO (-4313 4637);
FORCEPROP 1 LASTPIN (-4125 4625) $PN 2
J 0
(-4163 4637);
DISPLAY 0.787234 (-4163 4637);
PAINT MONO (-4163 4637);
FORCEPROP 1 LAST MATERIAL CHIP
J 0
(-3950 4625);
DISPLAY 0.510638 (-3950 4625);
FORCEPROP 1 LAST VALUE 10K
J 2
(-4050 4625);
DISPLAY 0.510638 (-4050 4625);
FORCEPROP 1 LAST TOLERANCE 1%
J 0
(-4025 4625);
DISPLAY 0.510638 (-4025 4625);
FORCEPROP 1 LAST PACK_TYPE 0402LF
J 0
(-4400 4750);
DISPLAY 0.510638 (-4400 4750);
DISPLAY INVISIBLE (-4400 4750);
FORCEPROP 1 LAST WATTAGE 1/16W
J 2
(-4025 4750);
DISPLAY 0.510638 (-4025 4750);
DISPLAY INVISIBLE (-4025 4750);
FORCEPROP 2 LAST CDS_LIB pure_quanta
J 0
(-4225 4625);
DISPLAY INVISIBLE (-4225 4625);
FORCEPROP 1 LAST PATH I7
J 0
(-4275 4775);
DISPLAY 0.978723 (-4275 4775);
PAINT WHITE (-4275 4775);
DISPLAY INVISIBLE (-4275 4775);
FORCEPROP 1 LAST PART_NUMBER CS31002FB08
J 0
(-4400 4700);
DISPLAY 0.510638 (-4400 4700);
DISPLAY INVISIBLE (-4400 4700);
FORCEADD TAP..1
R 2
(-1725 4400);
FORCEPROP 3 LASTPIN (-1675 4400) SIG_NAME P5E_CPU0_G3_TX_C_DN<6>
J 0
(-1665 4410);
DISPLAY 0.659574 (-1665 4410);
PAINT MONO (-1665 4410);
DISPLAY INVISIBLE (-1665 4410);
FORCEPROP 1 LASTPIN (-1675 4400) BN 6
J 2
(-1663 4408);
DISPLAY 0.680851 (-1663 4408);
PAINT GREEN (-1663 4408);
FORCEPROP 2 LAST CDS_LIB standard
J 0
(-1725 4400);
PAINT MONO (-1725 4400);
DISPLAY INVISIBLE (-1725 4400);
FORCEPROP 1 LAST BODY_TYPE PLUMBING
J 2
(-1725 4450);
DISPLAY 0.872340 (-1725 4450);
PAINT GREEN (-1725 4450);
DISPLAY INVISIBLE (-1725 4450);
FORCEPROP 1 LAST HDL_TAP TRUE
J 2
(-2050 4275);
DISPLAY 0.872340 (-2050 4275);
PAINT GREEN (-2050 4275);
DISPLAY INVISIBLE (-2050 4275);
FORCEPROP 1 LAST PATH I70
J 2
(-1723 4400);
DISPLAY 0.872340 (-1723 4400);
PAINT GREEN (-1723 4400);
DISPLAY INVISIBLE (-1723 4400);
FORCEADD TAP..1
R 2
(-1725 4250);
FORCEPROP 3 LASTPIN (-1675 4250) SIG_NAME P5E_CPU0_G3_TX_C_DN<7>
J 0
(-1665 4260);
DISPLAY 0.659574 (-1665 4260);
PAINT MONO (-1665 4260);
DISPLAY INVISIBLE (-1665 4260);
FORCEPROP 1 LASTPIN (-1675 4250) BN 7
J 2
(-1663 4258);
DISPLAY 0.680851 (-1663 4258);
PAINT GREEN (-1663 4258);
FORCEPROP 2 LAST CDS_LIB standard
J 0
(-1725 4250);
PAINT MONO (-1725 4250);
DISPLAY INVISIBLE (-1725 4250);
FORCEPROP 1 LAST BODY_TYPE PLUMBING
J 2
(-1725 4300);
DISPLAY 0.872340 (-1725 4300);
PAINT GREEN (-1725 4300);
DISPLAY INVISIBLE (-1725 4300);
FORCEPROP 1 LAST HDL_TAP TRUE
J 2
(-2050 4125);
DISPLAY 0.872340 (-2050 4125);
PAINT GREEN (-2050 4125);
DISPLAY INVISIBLE (-2050 4125);
FORCEPROP 1 LAST PATH I71
J 2
(-1723 4250);
DISPLAY 0.872340 (-1723 4250);
PAINT GREEN (-1723 4250);
DISPLAY INVISIBLE (-1723 4250);
FORCEADD TAP..1
R 2
(-1725 4550);
FORCEPROP 3 LASTPIN (-1675 4550) SIG_NAME P5E_CPU0_G3_TX_C_DN<5>
J 0
(-1665 4560);
DISPLAY 0.659574 (-1665 4560);
PAINT MONO (-1665 4560);
DISPLAY INVISIBLE (-1665 4560);
FORCEPROP 1 LASTPIN (-1675 4550) BN 5
J 2
(-1663 4558);
DISPLAY 0.680851 (-1663 4558);
PAINT GREEN (-1663 4558);
FORCEPROP 2 LAST CDS_LIB standard
J 0
(-1725 4550);
PAINT MONO (-1725 4550);
DISPLAY INVISIBLE (-1725 4550);
FORCEPROP 1 LAST BODY_TYPE PLUMBING
J 2
(-1725 4600);
DISPLAY 0.872340 (-1725 4600);
PAINT GREEN (-1725 4600);
DISPLAY INVISIBLE (-1725 4600);
FORCEPROP 1 LAST HDL_TAP TRUE
J 2
(-2050 4425);
DISPLAY 0.872340 (-2050 4425);
PAINT GREEN (-2050 4425);
DISPLAY INVISIBLE (-2050 4425);
FORCEPROP 1 LAST PATH I72
J 2
(-1723 4550);
DISPLAY 0.872340 (-1723 4550);
PAINT GREEN (-1723 4550);
DISPLAY INVISIBLE (-1723 4550);
FORCEADD TAP..1
R 2
(-1575 4300);
FORCEPROP 3 LASTPIN (-1525 4300) SIG_NAME P5E_CPU0_G3_TX_C_DP<7>
J 0
(-1515 4310);
DISPLAY 0.659574 (-1515 4310);
PAINT MONO (-1515 4310);
DISPLAY INVISIBLE (-1515 4310);
FORCEPROP 1 LASTPIN (-1525 4300) BN 7
J 2
(-1513 4308);
DISPLAY 0.680851 (-1513 4308);
PAINT GREEN (-1513 4308);
FORCEPROP 2 LAST CDS_LIB standard
J 0
(-1575 4300);
PAINT MONO (-1575 4300);
DISPLAY INVISIBLE (-1575 4300);
FORCEPROP 1 LAST BODY_TYPE PLUMBING
J 2
(-1575 4350);
DISPLAY 0.872340 (-1575 4350);
PAINT GREEN (-1575 4350);
DISPLAY INVISIBLE (-1575 4350);
FORCEPROP 1 LAST HDL_TAP TRUE
J 2
(-1900 4175);
DISPLAY 0.872340 (-1900 4175);
PAINT GREEN (-1900 4175);
DISPLAY INVISIBLE (-1900 4175);
FORCEPROP 1 LAST PATH I73
J 2
(-1573 4300);
DISPLAY 0.872340 (-1573 4300);
PAINT GREEN (-1573 4300);
DISPLAY INVISIBLE (-1573 4300);
FORCEADD TAP..1
R 2
(-1575 4450);
FORCEPROP 3 LASTPIN (-1525 4450) SIG_NAME P5E_CPU0_G3_TX_C_DP<6>
J 0
(-1515 4460);
DISPLAY 0.659574 (-1515 4460);
PAINT MONO (-1515 4460);
DISPLAY INVISIBLE (-1515 4460);
FORCEPROP 1 LASTPIN (-1525 4450) BN 6
J 2
(-1513 4458);
DISPLAY 0.680851 (-1513 4458);
PAINT GREEN (-1513 4458);
FORCEPROP 2 LAST CDS_LIB standard
J 0
(-1575 4450);
PAINT MONO (-1575 4450);
DISPLAY INVISIBLE (-1575 4450);
FORCEPROP 1 LAST BODY_TYPE PLUMBING
J 2
(-1575 4500);
DISPLAY 0.872340 (-1575 4500);
PAINT GREEN (-1575 4500);
DISPLAY INVISIBLE (-1575 4500);
FORCEPROP 1 LAST HDL_TAP TRUE
J 2
(-1900 4325);
DISPLAY 0.872340 (-1900 4325);
PAINT GREEN (-1900 4325);
DISPLAY INVISIBLE (-1900 4325);
FORCEPROP 1 LAST PATH I74
J 2
(-1573 4450);
DISPLAY 0.872340 (-1573 4450);
PAINT GREEN (-1573 4450);
DISPLAY INVISIBLE (-1573 4450);
FORCEADD TAP..1
R 2
(-1575 4600);
FORCEPROP 3 LASTPIN (-1525 4600) SIG_NAME P5E_CPU0_G3_TX_C_DP<5>
J 0
(-1515 4610);
DISPLAY 0.659574 (-1515 4610);
PAINT MONO (-1515 4610);
DISPLAY INVISIBLE (-1515 4610);
FORCEPROP 1 LASTPIN (-1525 4600) BN 5
J 2
(-1513 4608);
DISPLAY 0.680851 (-1513 4608);
PAINT GREEN (-1513 4608);
FORCEPROP 2 LAST CDS_LIB standard
J 0
(-1575 4600);
PAINT MONO (-1575 4600);
DISPLAY INVISIBLE (-1575 4600);
FORCEPROP 1 LAST BODY_TYPE PLUMBING
J 2
(-1575 4650);
DISPLAY 0.872340 (-1575 4650);
PAINT GREEN (-1575 4650);
DISPLAY INVISIBLE (-1575 4650);
FORCEPROP 1 LAST HDL_TAP TRUE
J 2
(-1900 4475);
DISPLAY 0.872340 (-1900 4475);
PAINT GREEN (-1900 4475);
DISPLAY INVISIBLE (-1900 4475);
FORCEPROP 1 LAST PATH I75
J 2
(-1573 4600);
DISPLAY 0.872340 (-1573 4600);
PAINT GREEN (-1573 4600);
DISPLAY INVISIBLE (-1573 4600);
FORCEADD TAP..1
R 2
(-1725 4700);
FORCEPROP 3 LASTPIN (-1675 4700) SIG_NAME P5E_CPU0_G3_TX_C_DN<4>
J 0
(-1665 4710);
DISPLAY 0.659574 (-1665 4710);
PAINT MONO (-1665 4710);
DISPLAY INVISIBLE (-1665 4710);
FORCEPROP 1 LASTPIN (-1675 4700) BN 4
J 2
(-1663 4708);
DISPLAY 0.680851 (-1663 4708);
PAINT GREEN (-1663 4708);
FORCEPROP 2 LAST CDS_LIB standard
J 0
(-1725 4700);
PAINT MONO (-1725 4700);
DISPLAY INVISIBLE (-1725 4700);
FORCEPROP 1 LAST BODY_TYPE PLUMBING
J 2
(-1725 4750);
DISPLAY 0.872340 (-1725 4750);
PAINT GREEN (-1725 4750);
DISPLAY INVISIBLE (-1725 4750);
FORCEPROP 1 LAST HDL_TAP TRUE
J 2
(-2050 4575);
DISPLAY 0.872340 (-2050 4575);
PAINT GREEN (-2050 4575);
DISPLAY INVISIBLE (-2050 4575);
FORCEPROP 1 LAST PATH I76
J 2
(-1723 4700);
DISPLAY 0.872340 (-1723 4700);
PAINT GREEN (-1723 4700);
DISPLAY INVISIBLE (-1723 4700);
FORCEADD TAP..1
R 2
(-1725 5000);
FORCEPROP 3 LASTPIN (-1675 5000) SIG_NAME P5E_CPU0_G3_TX_C_DN<3>
J 0
(-1665 5010);
DISPLAY 0.659574 (-1665 5010);
PAINT MONO (-1665 5010);
DISPLAY INVISIBLE (-1665 5010);
FORCEPROP 1 LASTPIN (-1675 5000) BN 3
J 2
(-1663 5008);
DISPLAY 0.680851 (-1663 5008);
PAINT GREEN (-1663 5008);
FORCEPROP 2 LAST CDS_LIB standard
J 0
(-1725 5000);
PAINT MONO (-1725 5000);
DISPLAY INVISIBLE (-1725 5000);
FORCEPROP 1 LAST BODY_TYPE PLUMBING
J 2
(-1725 5050);
DISPLAY 0.872340 (-1725 5050);
PAINT GREEN (-1725 5050);
DISPLAY INVISIBLE (-1725 5050);
FORCEPROP 1 LAST HDL_TAP TRUE
J 2
(-2050 4875);
DISPLAY 0.872340 (-2050 4875);
PAINT GREEN (-2050 4875);
DISPLAY INVISIBLE (-2050 4875);
FORCEPROP 1 LAST PATH I77
J 2
(-1723 5000);
DISPLAY 0.872340 (-1723 5000);
PAINT GREEN (-1723 5000);
DISPLAY INVISIBLE (-1723 5000);
FORCEADD TAP..1
R 2
(-1575 4750);
FORCEPROP 3 LASTPIN (-1525 4750) SIG_NAME P5E_CPU0_G3_TX_C_DP<4>
J 0
(-1515 4760);
DISPLAY 0.659574 (-1515 4760);
PAINT MONO (-1515 4760);
DISPLAY INVISIBLE (-1515 4760);
FORCEPROP 1 LASTPIN (-1525 4750) BN 4
J 2
(-1513 4758);
DISPLAY 0.680851 (-1513 4758);
PAINT GREEN (-1513 4758);
FORCEPROP 2 LAST CDS_LIB standard
J 0
(-1575 4750);
PAINT MONO (-1575 4750);
DISPLAY INVISIBLE (-1575 4750);
FORCEPROP 1 LAST BODY_TYPE PLUMBING
J 2
(-1575 4800);
DISPLAY 0.872340 (-1575 4800);
PAINT GREEN (-1575 4800);
DISPLAY INVISIBLE (-1575 4800);
FORCEPROP 1 LAST HDL_TAP TRUE
J 2
(-1900 4625);
DISPLAY 0.872340 (-1900 4625);
PAINT GREEN (-1900 4625);
DISPLAY INVISIBLE (-1900 4625);
FORCEPROP 1 LAST PATH I78
J 2
(-1573 4750);
DISPLAY 0.872340 (-1573 4750);
PAINT GREEN (-1573 4750);
DISPLAY INVISIBLE (-1573 4750);
FORCEADD TAP..1
R 2
(-1575 5050);
FORCEPROP 3 LASTPIN (-1525 5050) SIG_NAME P5E_CPU0_G3_TX_C_DP<3>
J 0
(-1515 5060);
DISPLAY 0.659574 (-1515 5060);
PAINT MONO (-1515 5060);
DISPLAY INVISIBLE (-1515 5060);
FORCEPROP 1 LASTPIN (-1525 5050) BN 3
J 2
(-1513 5058);
DISPLAY 0.680851 (-1513 5058);
PAINT GREEN (-1513 5058);
FORCEPROP 2 LAST CDS_LIB standard
J 0
(-1575 5050);
PAINT MONO (-1575 5050);
DISPLAY INVISIBLE (-1575 5050);
FORCEPROP 1 LAST BODY_TYPE PLUMBING
J 2
(-1575 5100);
DISPLAY 0.872340 (-1575 5100);
PAINT GREEN (-1575 5100);
DISPLAY INVISIBLE (-1575 5100);
FORCEPROP 1 LAST HDL_TAP TRUE
J 2
(-1900 4925);
DISPLAY 0.872340 (-1900 4925);
PAINT GREEN (-1900 4925);
DISPLAY INVISIBLE (-1900 4925);
FORCEPROP 1 LAST PATH I79
J 2
(-1573 5050);
DISPLAY 0.872340 (-1573 5050);
PAINT GREEN (-1573 5050);
DISPLAY INVISIBLE (-1573 5050);
FORCEADD Q_RES..1
(-4225 4725);
FORCEPROP 1 LAST LOCATION R1929
J 0
(-4500 4725);
DISPLAY 0.787234 (-4500 4725);
FORCEPROP 0 LAST $SEC 1
J 0
(-4025 4875);
DISPLAY 0.680851 (-4025 4875);
PAINT MONO (-4025 4875);
DISPLAY INVISIBLE (-4025 4875);
FORCEPROP 0 LAST CDS_SEC 1
J 0
(-4025 4875);
DISPLAY 1.021277 (-4025 4875);
DISPLAY INVISIBLE (-4025 4875);
FORCEPROP 1 LASTPIN (-4325 4725) $PN 1
J 0
(-4313 4737);
DISPLAY 0.787234 (-4313 4737);
PAINT MONO (-4313 4737);
FORCEPROP 1 LASTPIN (-4125 4725) $PN 2
J 0
(-4163 4737);
DISPLAY 0.787234 (-4163 4737);
PAINT MONO (-4163 4737);
FORCEPROP 1 LAST WATTAGE 1/16W
J 2
(-4025 4900);
DISPLAY 0.510638 (-4025 4900);
FORCEPROP 1 LAST TOLERANCE 1%
J 0
(-4025 4725);
DISPLAY 0.510638 (-4025 4725);
FORCEPROP 1 LAST MATERIAL CHIP
J 0
(-3950 4725);
DISPLAY 0.510638 (-3950 4725);
FORCEPROP 1 LAST VALUE 10K
J 2
(-4050 4725);
DISPLAY 0.510638 (-4050 4725);
FORCEPROP 1 LAST PACK_TYPE 0402LF
J 0
(-4400 4850);
DISPLAY 0.510638 (-4400 4850);
FORCEPROP 2 LAST CDS_LIB pure_quanta
J 0
(-4225 4725);
DISPLAY INVISIBLE (-4225 4725);
FORCEPROP 1 LAST PATH I8
J 0
(-4275 4875);
DISPLAY 0.978723 (-4275 4875);
PAINT WHITE (-4275 4875);
DISPLAY INVISIBLE (-4275 4875);
FORCEPROP 1 LAST PART_NUMBER CS31002FB08
J 0
(-4400 4800);
DISPLAY 0.510638 (-4400 4800);
DISPLAY INVISIBLE (-4400 4800);
FORCEADD TAP..1
R 2
(-1725 5150);
FORCEPROP 3 LASTPIN (-1675 5150) SIG_NAME P5E_CPU0_G3_TX_C_DN<2>
J 0
(-1665 5160);
DISPLAY 0.659574 (-1665 5160);
PAINT MONO (-1665 5160);
DISPLAY INVISIBLE (-1665 5160);
FORCEPROP 1 LASTPIN (-1675 5150) BN 2
J 2
(-1663 5158);
DISPLAY 0.680851 (-1663 5158);
PAINT GREEN (-1663 5158);
FORCEPROP 2 LAST CDS_LIB standard
J 0
(-1725 5150);
PAINT MONO (-1725 5150);
DISPLAY INVISIBLE (-1725 5150);
FORCEPROP 1 LAST BODY_TYPE PLUMBING
J 2
(-1725 5200);
DISPLAY 0.872340 (-1725 5200);
PAINT GREEN (-1725 5200);
DISPLAY INVISIBLE (-1725 5200);
FORCEPROP 1 LAST HDL_TAP TRUE
J 2
(-2050 5025);
DISPLAY 0.872340 (-2050 5025);
PAINT GREEN (-2050 5025);
DISPLAY INVISIBLE (-2050 5025);
FORCEPROP 1 LAST PATH I80
J 2
(-1723 5150);
DISPLAY 0.872340 (-1723 5150);
PAINT GREEN (-1723 5150);
DISPLAY INVISIBLE (-1723 5150);
FORCEADD TAP..1
R 2
(-1725 5450);
FORCEPROP 3 LASTPIN (-1675 5450) SIG_NAME P5E_CPU0_G3_TX_C_DN<0>
J 0
(-1665 5460);
DISPLAY 0.659574 (-1665 5460);
PAINT MONO (-1665 5460);
DISPLAY INVISIBLE (-1665 5460);
FORCEPROP 1 LASTPIN (-1675 5450) BN 0
J 2
(-1663 5458);
DISPLAY 0.680851 (-1663 5458);
PAINT GREEN (-1663 5458);
FORCEPROP 2 LAST CDS_LIB standard
J 0
(-1725 5450);
DISPLAY INVISIBLE (-1725 5450);
FORCEPROP 1 LAST BODY_TYPE PLUMBING
J 2
(-1725 5500);
DISPLAY 0.872340 (-1725 5500);
PAINT GREEN (-1725 5500);
DISPLAY INVISIBLE (-1725 5500);
FORCEPROP 1 LAST HDL_TAP TRUE
J 2
(-2050 5325);
DISPLAY 0.872340 (-2050 5325);
PAINT GREEN (-2050 5325);
DISPLAY INVISIBLE (-2050 5325);
FORCEPROP 1 LAST PATH I81
J 2
(-1723 5450);
DISPLAY 0.872340 (-1723 5450);
PAINT GREEN (-1723 5450);
DISPLAY INVISIBLE (-1723 5450);
FORCEADD TAP..1
R 2
(-1725 5300);
FORCEPROP 3 LASTPIN (-1675 5300) SIG_NAME P5E_CPU0_G3_TX_C_DN<1>
J 0
(-1665 5310);
DISPLAY 0.659574 (-1665 5310);
PAINT MONO (-1665 5310);
DISPLAY INVISIBLE (-1665 5310);
FORCEPROP 1 LASTPIN (-1675 5300) BN 1
J 2
(-1663 5308);
DISPLAY 0.680851 (-1663 5308);
PAINT GREEN (-1663 5308);
FORCEPROP 2 LAST CDS_LIB standard
J 0
(-1725 5300);
PAINT MONO (-1725 5300);
DISPLAY INVISIBLE (-1725 5300);
FORCEPROP 1 LAST BODY_TYPE PLUMBING
J 2
(-1725 5350);
DISPLAY 0.872340 (-1725 5350);
PAINT GREEN (-1725 5350);
DISPLAY INVISIBLE (-1725 5350);
FORCEPROP 1 LAST HDL_TAP TRUE
J 2
(-2050 5175);
DISPLAY 0.872340 (-2050 5175);
PAINT GREEN (-2050 5175);
DISPLAY INVISIBLE (-2050 5175);
FORCEPROP 1 LAST PATH I82
J 2
(-1723 5300);
DISPLAY 0.872340 (-1723 5300);
PAINT GREEN (-1723 5300);
DISPLAY INVISIBLE (-1723 5300);
FORCEADD TAP..1
R 2
(-1575 5200);
FORCEPROP 3 LASTPIN (-1525 5200) SIG_NAME P5E_CPU0_G3_TX_C_DP<2>
J 0
(-1515 5210);
DISPLAY 0.659574 (-1515 5210);
PAINT MONO (-1515 5210);
DISPLAY INVISIBLE (-1515 5210);
FORCEPROP 1 LASTPIN (-1525 5200) BN 2
J 2
(-1513 5208);
DISPLAY 0.680851 (-1513 5208);
PAINT GREEN (-1513 5208);
FORCEPROP 2 LAST CDS_LIB standard
J 0
(-1575 5200);
PAINT MONO (-1575 5200);
DISPLAY INVISIBLE (-1575 5200);
FORCEPROP 1 LAST BODY_TYPE PLUMBING
J 2
(-1575 5250);
DISPLAY 0.872340 (-1575 5250);
PAINT GREEN (-1575 5250);
DISPLAY INVISIBLE (-1575 5250);
FORCEPROP 1 LAST HDL_TAP TRUE
J 2
(-1900 5075);
DISPLAY 0.872340 (-1900 5075);
PAINT GREEN (-1900 5075);
DISPLAY INVISIBLE (-1900 5075);
FORCEPROP 1 LAST PATH I83
J 2
(-1573 5200);
DISPLAY 0.872340 (-1573 5200);
PAINT GREEN (-1573 5200);
DISPLAY INVISIBLE (-1573 5200);
FORCEADD TAP..1
R 2
(-1575 5350);
FORCEPROP 3 LASTPIN (-1525 5350) SIG_NAME P5E_CPU0_G3_TX_C_DP<1>
J 0
(-1515 5360);
DISPLAY 0.659574 (-1515 5360);
PAINT MONO (-1515 5360);
DISPLAY INVISIBLE (-1515 5360);
FORCEPROP 1 LASTPIN (-1525 5350) BN 1
J 2
(-1513 5358);
DISPLAY 0.680851 (-1513 5358);
PAINT GREEN (-1513 5358);
FORCEPROP 2 LAST CDS_LIB standard
J 0
(-1575 5350);
PAINT MONO (-1575 5350);
DISPLAY INVISIBLE (-1575 5350);
FORCEPROP 1 LAST BODY_TYPE PLUMBING
J 2
(-1575 5400);
DISPLAY 0.872340 (-1575 5400);
PAINT GREEN (-1575 5400);
DISPLAY INVISIBLE (-1575 5400);
FORCEPROP 1 LAST HDL_TAP TRUE
J 2
(-1900 5225);
DISPLAY 0.872340 (-1900 5225);
PAINT GREEN (-1900 5225);
DISPLAY INVISIBLE (-1900 5225);
FORCEPROP 1 LAST PATH I84
J 2
(-1573 5350);
DISPLAY 0.872340 (-1573 5350);
PAINT GREEN (-1573 5350);
DISPLAY INVISIBLE (-1573 5350);
FORCEADD TAP..1
R 2
(-1575 5500);
FORCEPROP 3 LASTPIN (-1525 5500) SIG_NAME P5E_CPU0_G3_TX_C_DP<0>
J 0
(-1515 5510);
DISPLAY 0.659574 (-1515 5510);
PAINT MONO (-1515 5510);
DISPLAY INVISIBLE (-1515 5510);
FORCEPROP 1 LASTPIN (-1525 5500) BN 0
J 2
(-1513 5508);
DISPLAY 0.680851 (-1513 5508);
PAINT GREEN (-1513 5508);
FORCEPROP 2 LAST CDS_LIB standard
J 0
(-1575 5500);
DISPLAY INVISIBLE (-1575 5500);
FORCEPROP 1 LAST BODY_TYPE PLUMBING
J 2
(-1575 5550);
DISPLAY 0.872340 (-1575 5550);
PAINT GREEN (-1575 5550);
DISPLAY INVISIBLE (-1575 5550);
FORCEPROP 1 LAST HDL_TAP TRUE
J 2
(-1900 5375);
DISPLAY 0.872340 (-1900 5375);
PAINT GREEN (-1900 5375);
DISPLAY INVISIBLE (-1900 5375);
FORCEPROP 1 LAST PATH I85
J 2
(-1573 5500);
DISPLAY 0.872340 (-1573 5500);
PAINT GREEN (-1573 5500);
DISPLAY INVISIBLE (-1573 5500);
FORCEADD UNIVERSAL_POWER..1
(-1425 7400);
FORCEPROP 3 LASTPIN (-1425 7350) SIG_NAME P12V_OCP_SFF_R\g
J 0
(-1415 7360);
DISPLAY 0.659574 (-1415 7360);
PAINT MONO (-1415 7360);
DISPLAY INVISIBLE (-1415 7360);
FORCEPROP 1 LAST HDL_POWER P12V_OCP_SFF_R
J 1
(-1425 7450);
DISPLAY 0.872340 (-1425 7450);
PAINT GREEN (-1425 7450);
FORCEPROP 2 LAST CDS_LIB pure_quanta_power
J 0
(-1425 7400);
DISPLAY INVISIBLE (-1425 7400);
FORCEPROP 1 LAST PATH I86
J 0
(-1375 7425);
DISPLAY 0.872340 (-1375 7425);
PAINT AQUA (-1375 7425);
DISPLAY INVISIBLE (-1375 7425);
FORCEADD Q_CAP..1
(825 1750);
FORCEPROP 1 LAST LOCATION C1213
J 0
(875 1850);
DISPLAY 0.787234 (875 1850);
FORCEPROP 2 LAST $SEC 1
J 0
(875 1950);
DISPLAY 0.680851 (875 1950);
PAINT MONO (875 1950);
DISPLAY INVISIBLE (875 1950);
FORCEPROP 2 LAST CDS_SEC 1
J 0
(875 1950);
DISPLAY 1.021277 (875 1950);
DISPLAY INVISIBLE (875 1950);
FORCEPROP 1 LASTPIN (825 1850) $PN 1
J 0
(835 1830);
DISPLAY 0.787234 (835 1830);
FORCEPROP 1 LASTPIN (825 1650) $PN 2
J 0
(835 1630);
DISPLAY 0.787234 (835 1630);
FORCEPROP 1 LAST VALUE 22UF
J 0
(875 1800);
DISPLAY 0.638298 (875 1800);
FORCEPROP 1 LAST VOLTAGE 16V
J 0
(875 1750);
DISPLAY 0.638298 (875 1750);
FORCEPROP 1 LAST TOLERANCE 20%
J 0
(875 1700);
DISPLAY 0.638298 (875 1700);
FORCEPROP 1 LAST PACK_TYPE C0805
J 0
(875 1600);
DISPLAY 0.638298 (875 1600);
FORCEPROP 1 LAST MATERIAL X6S
J 0
(875 1650);
DISPLAY 0.638298 (875 1650);
FORCEPROP 2 LAST CDS_LIB pure_quanta
J 0
(825 1750);
PAINT MONO (825 1750);
DISPLAY INVISIBLE (825 1750);
FORCEPROP 1 LAST PATH I87
J 0
(875 1900);
DISPLAY 0.978723 (875 1900);
PAINT WHITE (875 1900);
DISPLAY INVISIBLE (875 1900);
FORCEPROP 1 LAST PART_NUMBER CH6223MEA00
J 0
(875 1550);
DISPLAY 0.808511 (875 1550);
DISPLAY INVISIBLE (875 1550);
FORCEADD Q_CAP..1
(1100 1750);
FORCEPROP 1 LAST LOCATION C34
J 0
(1150 1850);
DISPLAY 0.787234 (1150 1850);
FORCEPROP 2 LAST $SEC 1
J 0
(1150 1950);
DISPLAY 0.680851 (1150 1950);
PAINT MONO (1150 1950);
DISPLAY INVISIBLE (1150 1950);
FORCEPROP 2 LAST CDS_SEC 1
J 0
(1150 1950);
DISPLAY 1.021277 (1150 1950);
DISPLAY INVISIBLE (1150 1950);
FORCEPROP 1 LASTPIN (1100 1850) $PN 1
J 0
(1110 1830);
DISPLAY 0.787234 (1110 1830);
FORCEPROP 1 LASTPIN (1100 1650) $PN 2
J 0
(1110 1630);
DISPLAY 0.787234 (1110 1630);
FORCEPROP 1 LAST VOLTAGE 16V
J 0
(1150 1750);
DISPLAY 0.638298 (1150 1750);
FORCEPROP 1 LAST MATERIAL X6S
J 0
(1150 1650);
DISPLAY 0.638298 (1150 1650);
FORCEPROP 1 LAST TOLERANCE 20%
J 0
(1150 1700);
DISPLAY 0.638298 (1150 1700);
FORCEPROP 1 LAST VALUE 22UF
J 0
(1150 1800);
DISPLAY 0.638298 (1150 1800);
FORCEPROP 1 LAST PACK_TYPE C0805
J 0
(1150 1550);
DISPLAY 0.638298 (1150 1550);
FORCEPROP 2 LAST CDS_LIB pure_quanta
J 0
(1100 1750);
PAINT MONO (1100 1750);
DISPLAY INVISIBLE (1100 1750);
FORCEPROP 1 LAST PATH I88
J 0
(1150 1900);
DISPLAY 0.978723 (1150 1900);
PAINT WHITE (1150 1900);
DISPLAY INVISIBLE (1150 1900);
FORCEPROP 1 LAST PART_NUMBER CH6223MEA00
J 0
(1150 1600);
DISPLAY 0.638298 (1150 1600);
DISPLAY INVISIBLE (1150 1600);
FORCEADD Q_CAP..1
(1500 1750);
FORCEPROP 1 LAST LOCATION C21
J 0
(1550 1850);
DISPLAY 0.787234 (1550 1850);
FORCEPROP 2 LAST $SEC 1
J 0
(1550 1950);
DISPLAY 0.680851 (1550 1950);
PAINT MONO (1550 1950);
DISPLAY INVISIBLE (1550 1950);
FORCEPROP 2 LAST CDS_SEC 1
J 0
(1550 1950);
DISPLAY 1.021277 (1550 1950);
DISPLAY INVISIBLE (1550 1950);
FORCEPROP 1 LASTPIN (1500 1850) $PN 1
J 0
(1510 1830);
DISPLAY 0.787234 (1510 1830);
FORCEPROP 1 LASTPIN (1500 1650) $PN 2
J 0
(1510 1630);
DISPLAY 0.787234 (1510 1630);
FORCEPROP 1 LAST PACK_TYPE 0402
J 0
(1550 1600);
DISPLAY 0.638298 (1550 1600);
FORCEPROP 1 LAST MATERIAL X7R
J 0
(1550 1650);
DISPLAY 0.638298 (1550 1650);
FORCEPROP 1 LAST VALUE 0.1UF
J 0
(1550 1800);
DISPLAY 0.638298 (1550 1800);
FORCEPROP 1 LAST VOLTAGE 25V
J 0
(1550 1750);
DISPLAY 0.638298 (1550 1750);
FORCEPROP 1 LAST TOLERANCE 10%
J 0
(1550 1700);
DISPLAY 0.638298 (1550 1700);
FORCEPROP 2 LAST CDS_LIB pure_quanta
J 0
(1500 1750);
PAINT MONO (1500 1750);
DISPLAY INVISIBLE (1500 1750);
FORCEPROP 1 LAST PATH I89
J 0
(1550 1900);
DISPLAY 0.978723 (1550 1900);
PAINT WHITE (1550 1900);
DISPLAY INVISIBLE (1550 1900);
FORCEPROP 1 LAST PART_NUMBER CH4104K1B00
J 0
(1550 1600);
DISPLAY 0.808511 (1550 1600);
DISPLAY INVISIBLE (1550 1600);
FORCEADD OFFPAGE..1
(-4050 7050);
FORCEPROP 2 LAST $XR0 82 
J 0
(-4301 7050);
DISPLAY 0.638298 (-4301 7050);
PAINT MONO (-4301 7050);
FORCEPROP 2 LAST $XR1 131 
J 0
(-4421 7050);
DISPLAY 0.638298 (-4421 7050);
PAINT MONO (-4421 7050);
FORCEPROP 2 LAST CDS_LIB standard
J 0
(-4050 7050);
DISPLAY INVISIBLE (-4050 7050);
FORCEPROP 1 LAST OFFPAGE TRUE
J 0
(-3725 6925);
DISPLAY 0.872340 (-3725 6925);
DISPLAY INVISIBLE (-3725 6925);
FORCEPROP 1 LAST COMMENT_BODY TRUE
J 0
(-3925 6950);
DISPLAY 0.872340 (-3925 6950);
PAINT GREEN (-3925 6950);
DISPLAY INVISIBLE (-3925 6950);
FORCEPROP 2 LAST PATH I9
J 0
(-4300 7100);
DISPLAY 0.680851 (-4300 7100);
DISPLAY INVISIBLE (-4300 7100);
FORCEADD Q_CAP..1
(2050 1750);
FORCEPROP 1 LAST LOCATION C1235
J 0
(2100 1850);
DISPLAY 0.787234 (2100 1850);
FORCEPROP 2 LAST $SEC 1
J 0
(2100 1950);
DISPLAY 0.680851 (2100 1950);
PAINT MONO (2100 1950);
DISPLAY INVISIBLE (2100 1950);
FORCEPROP 2 LAST CDS_SEC 1
J 0
(2100 1950);
DISPLAY 1.021277 (2100 1950);
DISPLAY INVISIBLE (2100 1950);
FORCEPROP 1 LASTPIN (2050 1850) $PN 1
J 0
(2060 1830);
DISPLAY 0.787234 (2060 1830);
FORCEPROP 1 LASTPIN (2050 1650) $PN 2
J 0
(2060 1630);
DISPLAY 0.787234 (2060 1630);
FORCEPROP 1 LAST VALUE 0.1UF
J 0
(2100 1800);
DISPLAY 0.638298 (2100 1800);
FORCEPROP 1 LAST VOLTAGE 25V
J 0
(2100 1750);
DISPLAY 0.638298 (2100 1750);
FORCEPROP 1 LAST TOLERANCE 10%
J 0
(2100 1700);
DISPLAY 0.638298 (2100 1700);
FORCEPROP 1 LAST PACK_TYPE 0402
J 0
(2100 1600);
DISPLAY 0.638298 (2100 1600);
FORCEPROP 1 LAST MATERIAL X7R
J 0
(2100 1650);
DISPLAY 0.638298 (2100 1650);
FORCEPROP 2 LAST CDS_LIB pure_quanta
J 0
(2050 1750);
PAINT MONO (2050 1750);
DISPLAY INVISIBLE (2050 1750);
FORCEPROP 1 LAST PATH I90
J 0
(2100 1900);
DISPLAY 0.978723 (2100 1900);
PAINT WHITE (2100 1900);
DISPLAY INVISIBLE (2100 1900);
FORCEPROP 1 LAST PART_NUMBER CH4104K1B00
J 0
(2100 1600);
DISPLAY 0.808511 (2100 1600);
DISPLAY INVISIBLE (2100 1600);
FORCEADD UNIVERSAL_GND..1
(575 2225);
FORCEPROP 3 LASTPIN (575 2275) SIG_NAME GND\g
J 0
(585 2285);
DISPLAY 0.659574 (585 2285);
PAINT MONO (585 2285);
DISPLAY INVISIBLE (585 2285);
FORCEPROP 2 LAST ROOM IO_SLOT
J 1
(350 2300);
DISPLAY 0.744681 (350 2300);
FORCEPROP 2 LAST CDS_LIB pure_quanta_power
J 0
(575 2225);
PAINT MONO (575 2225);
DISPLAY INVISIBLE (575 2225);
FORCEPROP 1 LAST HDL_POWER GND
J 1
(600 2150);
DISPLAY 0.872340 (600 2150);
PAINT GREEN (600 2150);
DISPLAY INVISIBLE (600 2150);
FORCEPROP 1 LAST PATH I91
J 0
(650 2225);
DISPLAY 0.872340 (650 2225);
PAINT AQUA (650 2225);
DISPLAY INVISIBLE (650 2225);
FORCEADD UNIVERSAL_POWER..1
(825 2100);
FORCEPROP 3 LASTPIN (825 2050) SIG_NAME P12V_OCP_SFF_R\g
J 0
(835 2060);
DISPLAY 0.659574 (835 2060);
PAINT MONO (835 2060);
DISPLAY INVISIBLE (835 2060);
FORCEPROP 1 LAST HDL_POWER P12V_OCP_SFF_R
J 1
(875 2150);
DISPLAY 0.872340 (875 2150);
PAINT GREEN (875 2150);
FORCEPROP 2 LAST CDS_LIB pure_quanta_power
J 0
(825 2100);
PAINT MONO (825 2100);
DISPLAY INVISIBLE (825 2100);
FORCEPROP 1 LAST PATH I92
J 0
(875 2125);
DISPLAY 0.872340 (875 2125);
PAINT AQUA (875 2125);
DISPLAY INVISIBLE (875 2125);
FORCEADD TAP..1
(775 3000);
FORCEPROP 3 LASTPIN (725 3000) SIG_NAME P5E_CPU0_G3_RX_DP<14>
J 0
(735 3010);
DISPLAY 0.659574 (735 3010);
PAINT MONO (735 3010);
DISPLAY INVISIBLE (735 3010);
FORCEPROP 1 LASTPIN (725 3000) BN 14
J 0
(713 3008);
DISPLAY 0.680851 (713 3008);
PAINT GREEN (713 3008);
FORCEPROP 2 LAST CDS_LIB standard
J 0
(775 3000);
PAINT MONO (775 3000);
DISPLAY INVISIBLE (775 3000);
FORCEPROP 1 LAST BODY_TYPE PLUMBING
J 0
(775 3050);
DISPLAY 0.872340 (775 3050);
PAINT GREEN (775 3050);
DISPLAY INVISIBLE (775 3050);
FORCEPROP 1 LAST HDL_TAP TRUE
J 0
(1100 2875);
DISPLAY 0.872340 (1100 2875);
PAINT GREEN (1100 2875);
DISPLAY INVISIBLE (1100 2875);
FORCEPROP 1 LAST PATH I93
J 0
(773 3000);
DISPLAY 0.872340 (773 3000);
PAINT GREEN (773 3000);
DISPLAY INVISIBLE (773 3000);
FORCEADD TAP..1
(925 2900);
FORCEPROP 3 LASTPIN (875 2900) SIG_NAME P5E_CPU0_G3_RX_DN<15>
J 0
(885 2910);
DISPLAY 0.659574 (885 2910);
PAINT MONO (885 2910);
DISPLAY INVISIBLE (885 2910);
FORCEPROP 1 LASTPIN (875 2900) BN 15
J 0
(863 2908);
DISPLAY 0.680851 (863 2908);
PAINT GREEN (863 2908);
FORCEPROP 2 LAST CDS_LIB standard
J 0
(925 2900);
PAINT MONO (925 2900);
DISPLAY INVISIBLE (925 2900);
FORCEPROP 1 LAST BODY_TYPE PLUMBING
J 0
(925 2950);
DISPLAY 0.872340 (925 2950);
PAINT GREEN (925 2950);
DISPLAY INVISIBLE (925 2950);
FORCEPROP 1 LAST HDL_TAP TRUE
J 0
(1250 2775);
DISPLAY 0.872340 (1250 2775);
PAINT GREEN (1250 2775);
DISPLAY INVISIBLE (1250 2775);
FORCEPROP 1 LAST PATH I94
J 0
(923 2900);
DISPLAY 0.872340 (923 2900);
PAINT GREEN (923 2900);
DISPLAY INVISIBLE (923 2900);
FORCEADD TAP..1
(925 3050);
FORCEPROP 3 LASTPIN (875 3050) SIG_NAME P5E_CPU0_G3_RX_DN<14>
J 0
(885 3060);
DISPLAY 0.659574 (885 3060);
PAINT MONO (885 3060);
DISPLAY INVISIBLE (885 3060);
FORCEPROP 1 LASTPIN (875 3050) BN 14
J 0
(863 3058);
DISPLAY 0.680851 (863 3058);
PAINT GREEN (863 3058);
FORCEPROP 2 LAST CDS_LIB standard
J 0
(925 3050);
PAINT MONO (925 3050);
DISPLAY INVISIBLE (925 3050);
FORCEPROP 1 LAST BODY_TYPE PLUMBING
J 0
(925 3100);
DISPLAY 0.872340 (925 3100);
PAINT GREEN (925 3100);
DISPLAY INVISIBLE (925 3100);
FORCEPROP 1 LAST HDL_TAP TRUE
J 0
(1250 2925);
DISPLAY 0.872340 (1250 2925);
PAINT GREEN (1250 2925);
DISPLAY INVISIBLE (1250 2925);
FORCEPROP 1 LAST PATH I95
J 0
(923 3050);
DISPLAY 0.872340 (923 3050);
PAINT GREEN (923 3050);
DISPLAY INVISIBLE (923 3050);
FORCEADD TAP..1
(775 3150);
FORCEPROP 3 LASTPIN (725 3150) SIG_NAME P5E_CPU0_G3_RX_DP<13>
J 0
(735 3160);
DISPLAY 0.659574 (735 3160);
PAINT MONO (735 3160);
DISPLAY INVISIBLE (735 3160);
FORCEPROP 1 LASTPIN (725 3150) BN 13
J 0
(713 3158);
DISPLAY 0.680851 (713 3158);
PAINT GREEN (713 3158);
FORCEPROP 2 LAST CDS_LIB standard
J 0
(775 3150);
PAINT MONO (775 3150);
DISPLAY INVISIBLE (775 3150);
FORCEPROP 1 LAST BODY_TYPE PLUMBING
J 0
(775 3200);
DISPLAY 0.872340 (775 3200);
PAINT GREEN (775 3200);
DISPLAY INVISIBLE (775 3200);
FORCEPROP 1 LAST HDL_TAP TRUE
J 0
(1100 3025);
DISPLAY 0.872340 (1100 3025);
PAINT GREEN (1100 3025);
DISPLAY INVISIBLE (1100 3025);
FORCEPROP 1 LAST PATH I96
J 0
(773 3150);
DISPLAY 0.872340 (773 3150);
PAINT GREEN (773 3150);
DISPLAY INVISIBLE (773 3150);
FORCEADD TAP..1
(775 3300);
FORCEPROP 3 LASTPIN (725 3300) SIG_NAME P5E_CPU0_G3_RX_DP<12>
J 0
(735 3310);
DISPLAY 0.659574 (735 3310);
PAINT MONO (735 3310);
DISPLAY INVISIBLE (735 3310);
FORCEPROP 1 LASTPIN (725 3300) BN 12
J 0
(713 3308);
DISPLAY 0.680851 (713 3308);
PAINT GREEN (713 3308);
FORCEPROP 2 LAST CDS_LIB standard
J 0
(775 3300);
PAINT MONO (775 3300);
DISPLAY INVISIBLE (775 3300);
FORCEPROP 1 LAST BODY_TYPE PLUMBING
J 0
(775 3350);
DISPLAY 0.872340 (775 3350);
PAINT GREEN (775 3350);
DISPLAY INVISIBLE (775 3350);
FORCEPROP 1 LAST HDL_TAP TRUE
J 0
(1100 3175);
DISPLAY 0.872340 (1100 3175);
PAINT GREEN (1100 3175);
DISPLAY INVISIBLE (1100 3175);
FORCEPROP 1 LAST PATH I97
J 0
(773 3300);
DISPLAY 0.872340 (773 3300);
PAINT GREEN (773 3300);
DISPLAY INVISIBLE (773 3300);
FORCEADD TAP..1
(775 3450);
FORCEPROP 3 LASTPIN (725 3450) SIG_NAME P5E_CPU0_G3_RX_DP<11>
J 0
(735 3460);
DISPLAY 0.659574 (735 3460);
PAINT MONO (735 3460);
DISPLAY INVISIBLE (735 3460);
FORCEPROP 1 LASTPIN (725 3450) BN 11
J 0
(713 3458);
DISPLAY 0.680851 (713 3458);
PAINT GREEN (713 3458);
FORCEPROP 2 LAST CDS_LIB standard
J 0
(775 3450);
PAINT MONO (775 3450);
DISPLAY INVISIBLE (775 3450);
FORCEPROP 1 LAST BODY_TYPE PLUMBING
J 0
(775 3500);
DISPLAY 0.872340 (775 3500);
PAINT GREEN (775 3500);
DISPLAY INVISIBLE (775 3500);
FORCEPROP 1 LAST HDL_TAP TRUE
J 0
(1100 3325);
DISPLAY 0.872340 (1100 3325);
PAINT GREEN (1100 3325);
DISPLAY INVISIBLE (1100 3325);
FORCEPROP 1 LAST PATH I98
J 0
(773 3450);
DISPLAY 0.872340 (773 3450);
PAINT GREEN (773 3450);
DISPLAY INVISIBLE (773 3450);
FORCEADD TAP..1
(925 3200);
FORCEPROP 3 LASTPIN (875 3200) SIG_NAME P5E_CPU0_G3_RX_DN<13>
J 0
(885 3210);
DISPLAY 0.659574 (885 3210);
PAINT MONO (885 3210);
DISPLAY INVISIBLE (885 3210);
FORCEPROP 1 LASTPIN (875 3200) BN 13
J 0
(863 3208);
DISPLAY 0.680851 (863 3208);
PAINT GREEN (863 3208);
FORCEPROP 2 LAST CDS_LIB standard
J 0
(925 3200);
PAINT MONO (925 3200);
DISPLAY INVISIBLE (925 3200);
FORCEPROP 1 LAST BODY_TYPE PLUMBING
J 0
(925 3250);
DISPLAY 0.872340 (925 3250);
PAINT GREEN (925 3250);
DISPLAY INVISIBLE (925 3250);
FORCEPROP 1 LAST HDL_TAP TRUE
J 0
(1250 3075);
DISPLAY 0.872340 (1250 3075);
PAINT GREEN (1250 3075);
DISPLAY INVISIBLE (1250 3075);
FORCEPROP 1 LAST PATH I99
J 0
(923 3200);
DISPLAY 0.872340 (923 3200);
PAINT GREEN (923 3200);
DISPLAY INVISIBLE (923 3200);
FORCEADD DNS..2
(-4300 2225);
PAINT RED (-4300 2225);
FORCEPROP 2 LAST CDS_LIB mstr_misc
J 0
(-4300 2225);
PAINT MONO (-4300 2225);
DISPLAY INVISIBLE (-4300 2225);
FORCEPROP 1 LAST COMMENT_BODY TRUE
R 1
J 0
(-4225 2000);
DISPLAY 0.872340 (-4225 2000);
PAINT GREEN (-4225 2000);
DISPLAY INVISIBLE (-4225 2000);
FORCEADD DNS..2
(-3825 2225);
PAINT RED (-3825 2225);
FORCEPROP 2 LAST CDS_LIB mstr_misc
J 0
(-3825 2225);
PAINT MONO (-3825 2225);
DISPLAY INVISIBLE (-3825 2225);
FORCEPROP 1 LAST COMMENT_BODY TRUE
R 1
J 0
(-3750 2000);
DISPLAY 0.872340 (-3750 2000);
PAINT GREEN (-3750 2000);
DISPLAY INVISIBLE (-3750 2000);
FORCEADD QUANTA_TITLE_BLOCK_C..1
(4375 1025);
FORCEPROP 0 LAST CDS_CON_LAST_MODIFIED Thu Sep 14 16:12:25 2023
J 0
(2490 1040);
PAINT MONO (2490 1040);
DISPLAY INVISIBLE (2490 1040);
FORCEPROP 2 LAST CUSTOM_TXT_CDS <XR_PAGE_TITLE>
J 0
(-3515 6275);
DISPLAY 0.638298 (-3515 6275);
PAINT PINK (-3515 6275);
DISPLAY INVISIBLE (-3515 6275);
FORCEPROP 2 LAST CUSTOM_TXT_CDS <CON_LAST_MODIFIED>
J 0
(2490 1040);
DISPLAY 0.978723 (2490 1040);
FORCEPROP 2 LAST CUSTOM_TXT_CDS <NAME_1>
J 0
(1200 1200);
FORCEPROP 2 LAST CUSTOM_TXT_CDS <Q_NUMBER>
J 0
(2972 1128);
DISPLAY 1.212766 (2972 1128);
FORCEPROP 2 LAST CUSTOM_TXT_CDS <CON_PAGE_NUM> OF <CON_TOTAL_PAGES>
J 0
(3929 1043);
DISPLAY 0.978723 (3929 1043);
FORCEPROP 2 LAST CUSTOM_TXT_CDS <Q_REV>
J 0
(4191 1128);
DISPLAY 1.212766 (4191 1128);
FORCEPROP 2 LAST CUSTOM_TXT_CDS <Q_PROJ>
J 0
(1993 1127);
DISPLAY 1.212766 (1993 1127);
FORCEPROP 2 LAST CUSTOM_TXT_CDS <NAME_2>
J 0
(1200 1075);
FORCEPROP 1 LAST Q_TITLE PCIE - SFF OCP3.0_X16_CPU0 (1/3)
J 0
(-4966 1051);
DISPLAY 1.957447 (-4966 1051);
PAINT GREEN (-4966 1051);
FORCEPROP 2 LAST PAGE_BORDER TRUE
J 0
(-3515 6275);
DISPLAY 0.638298 (-3515 6275);
PAINT PINK (-3515 6275);
DISPLAY INVISIBLE (-3515 6275);
FORCEPROP 1 LAST CDS_LMAN_SYM_OUTLINE -9475,6775,100,-125
J 0
(4375 1025);
DISPLAY 0.468085 (4375 1025);
PAINT GREEN (4375 1025);
DISPLAY INVISIBLE (4375 1025);
FORCEPROP 2 LAST CDS_LIB pure_quanta
J 0
(4375 1025);
PAINT MONO (4375 1025);
DISPLAY INVISIBLE (4375 1025);
FORCEPROP 2 LAST CDS_XR_PAGE_TITLE CR-131 : @T6G_MB_LIB.T6G(SCH_1):PAGE131
J 0
(-3515 6275);
DISPLAY 0.638298 (-3515 6275);
PAINT PINK (-3515 6275);
DISPLAY INVISIBLE (-3515 6275);
FORCEPROP 1 LAST Q_DEPT BU9
J 1
(612 1074);
DISPLAY 1.957447 (612 1074);
PAINT GREEN (612 1074);
DISPLAY INVISIBLE (612 1074);
FORCEPROP 1 LAST COMMENT_BODY TRUE
J 0
(4387 1012);
DISPLAY 0.978723 (4387 1012);
PAINT GREEN (4387 1012);
DISPLAY INVISIBLE (4387 1012);
FORCEADD CAD_NOTE..1
(1450 2150);
FORCEPROP 0 LAST S1 PLACE THE BULK CAPS CLOSE TO SLOT
J 0
(1300 2025);
DISPLAY 0.808511 (1300 2025);
PAINT WHITE (1300 2025);
FORCEPROP 2 LAST CDS_LIB pure_quanta_power
J 0
(1450 2150);
PAINT MONO (1450 2150);
DISPLAY INVISIBLE (1450 2150);
FORCEPROP 1 LAST COMMENT_BODY TRUE
J 0
(1475 2250);
DISPLAY 0.978723 (1475 2250);
DISPLAY INVISIBLE (1475 2250);
WIRE 17 -1 (975 3375)(975 3225);
WIRE 17 -1 (975 3525)(975 3375);
WIRE 17 -1 (975 3225)(975 3075);
WIRE 17 -1 (975 2925)(975 3075);
WIRE 17 -1 (975 3675)(975 3525);
WIRE 17 -1 (975 3675)(975 3825);
WIRE 17 -1 (975 3825)(975 3975);
WIRE 17 -1 (975 3975)(975 4325);
WIRE 17 -1 (975 4325)(975 4475);
WIRE 17 -1 (975 4475)(975 4625);
WIRE 17 -1 (975 4625)(975 4775);
WIRE 17 -1 (975 4775)(975 5075);
WIRE 17 -1 (975 5225)(975 5075);
WIRE 17 -1 (975 5225)(975 5375);
WIRE 17 -1 (975 5525)(975 5375);
WIRE 17 -1 (1925 5525)(975 5525);
FORCEPROP 2 LAST SIG_NAME P5E_CPU0_G3_RX_DN<15:0>
J 0
(1065 5535);
DISPLAY 0.638298 (1065 5535);
PAINT WHITE (1065 5535);
WIRE 17 -1 (825 3625)(825 3775);
WIRE 17 -1 (825 3625)(825 3475);
WIRE 17 -1 (825 3775)(825 3925);
WIRE 17 -1 (825 3925)(825 4275);
WIRE 17 -1 (825 3475)(825 3325);
WIRE 17 -1 (825 3325)(825 3175);
WIRE 17 -1 (825 4425)(825 4275);
WIRE 17 -1 (825 4425)(825 4575);
WIRE 17 -1 (825 3175)(825 3025);
WIRE 17 -1 (825 2875)(825 3025);
WIRE 17 -1 (825 4575)(825 4725);
WIRE 17 -1 (825 4725)(825 5025);
WIRE 17 -1 (825 5025)(825 5175);
WIRE 17 -1 (825 5325)(825 5175);
WIRE 17 -1 (825 5325)(825 5475);
WIRE 17 -1 (1925 5475)(825 5475);
FORCEPROP 2 LAST SIG_NAME P5E_CPU0_G3_RX_DP<15:0>
J 0
(1065 5485);
DISPLAY 0.638298 (1065 5485);
PAINT WHITE (1065 5485);
WIRE 17 -1 (-1775 5325)(-1775 5475);
WIRE 17 -1 (-1775 5175)(-1775 5325);
WIRE 17 -1 (-1775 5475)(-2725 5475);
FORCEPROP 2 LAST SIG_NAME P5E_CPU0_G3_TX_C_DN<15:0>
J 0
(-2660 5485);
DISPLAY 0.680851 (-2660 5485);
PAINT WHITE (-2660 5485);
WIRE 17 -1 (-1625 5375)(-1625 5525);
WIRE 17 -1 (-1625 5225)(-1625 5375);
WIRE 17 -1 (-2725 5525)(-1625 5525);
FORCEPROP 2 LAST SIG_NAME P5E_CPU0_G3_TX_C_DP<15:0>
J 0
(-2660 5535);
DISPLAY 0.680851 (-2660 5535);
PAINT WHITE (-2660 5535);
WIRE 17 -1 (-1775 5025)(-1775 5175);
WIRE 17 -1 (-1625 5075)(-1625 5225);
WIRE 17 -1 (-1775 4725)(-1775 5025);
WIRE 17 -1 (-1775 4575)(-1775 4725);
WIRE 17 -1 (-1775 4425)(-1775 4575);
WIRE 17 -1 (-1775 4275)(-1775 4425);
WIRE 17 -1 (-1775 3925)(-1775 4275);
WIRE 17 -1 (-1775 3925)(-1775 3775);
WIRE 17 -1 (-1775 3775)(-1775 3625);
WIRE 17 -1 (-1775 3625)(-1775 3475);
WIRE 17 -1 (-1775 3475)(-1775 3325);
WIRE 17 -1 (-1775 3325)(-1775 3175);
WIRE 17 -1 (-1775 3175)(-1775 3025);
WIRE 17 -1 (-1775 3025)(-1775 2875);
WIRE 17 -1 (-1625 4775)(-1625 5075);
WIRE 17 -1 (-1625 4625)(-1625 4775);
WIRE 17 -1 (-1625 4475)(-1625 4625);
WIRE 17 -1 (-1625 4325)(-1625 4475);
WIRE 17 -1 (-1625 3975)(-1625 4325);
WIRE 17 -1 (-1625 3825)(-1625 3975);
WIRE 17 -1 (-1625 3675)(-1625 3825);
WIRE 17 -1 (-1625 3525)(-1625 3675);
WIRE 17 -1 (-1625 3375)(-1625 3525);
WIRE 17 -1 (-1625 3375)(-1625 3225);
WIRE 17 -1 (-1625 3225)(-1625 3075);
WIRE 17 -1 (-1625 2925)(-1625 3075);
WIRE 16 -1 (-4300 1550)(-4300 1625);
WIRE 16 -1 (-3825 1550)(-3825 1625);
WIRE 16 -1 (3125 5375)(3125 5500);
WIRE 16 -1 (-2975 7050)(-4000 7050);
FORCEPROP 2 LAST SIG_NAME OCP_SFF_MAIN_PWR_EN
J 0
(-3935 7060);
DISPLAY 0.553191 (-3935 7060);
PAINT WHITE (-3935 7060);
WIRE 16 -1 (-4000 7100)(-1000 7100);
FORCEPROP 2 LAST SIG_NAME FM_OCP_SFF_PWR_GOOD
J 0
(-2210 7110);
DISPLAY 0.680851 (-2210 7110);
PAINT WHITE (-2210 7110);
WIRE 16 -1 (1875 5950)(3225 5950);
FORCEPROP 2 LAST SIG_NAME SMB_OCP_SFF_3V3AUX_BUF_SDA
J 0
(2465 5960);
DISPLAY 0.553191 (2465 5960);
PAINT WHITE (2465 5960);
WIRE 16 -1 (1875 6000)(3225 6000);
FORCEPROP 2 LAST SIG_NAME SMB_OCP_SFF_3V3AUX_BUF_SCL
J 0
(2465 6010);
DISPLAY 0.553191 (2465 6010);
PAINT WHITE (2465 6010);
WIRE 16 -1 (300 5900)(3225 5900);
FORCEPROP 2 LAST SIG_NAME RST_SMB_OCP_SFF_N
J 0
(665 5910);
DISPLAY 0.553191 (665 5910);
PAINT WHITE (665 5910);
WIRE 16 -1 (3125 5700)(3125 5850);
WIRE 16 -1 (3125 5850)(300 5850);
FORCEPROP 2 LAST SIG_NAME OCP_SFF_PRSNTA_R_N
J 0
(665 5860);
DISPLAY 0.510638 (665 5860);
PAINT WHITE (665 5860);
FORCEPROP 2 LASTPROP $XRERR UNIQUE?
J 0
(425 5860);
DISPLAY 0.638298 (425 5860);
PAINT MONO (425 5860);
DISPLAY INVISIBLE (425 5860);
WIRE 16 -1 (300 6550)(1375 6550);
FORCEPROP 2 LAST SIG_NAME CLK_100M_CPU0_CLK05_DP
J 0
(615 6560);
DISPLAY 0.680851 (615 6560);
PAINT WHITE (615 6560);
WIRE 16 -1 (300 6450)(1375 6450);
FORCEPROP 2 LAST SIG_NAME CLK_50M_NCSI_OCP_SFF_ISO
J 0
(665 6460);
DISPLAY 0.510638 (665 6460);
PAINT WHITE (665 6460);
WIRE 16 -1 (1675 6000)(300 6000);
FORCEPROP 2 LAST SIG_NAME SMB_OCP_SFF_3V3AUX_BUF_R_SCL
J 0
(665 6010);
DISPLAY 0.553191 (665 6010);
PAINT WHITE (665 6010);
FORCEPROP 2 LASTPROP $XRERR UNIQUE?
J 0
(425 6010);
DISPLAY 0.638298 (425 6010);
PAINT MONO (425 6010);
DISPLAY INVISIBLE (425 6010);
WIRE 16 -1 (575 6500)(575 6650);
WIRE 16 -1 (575 6500)(575 6300);
WIRE 16 -1 (300 6500)(575 6500);
WIRE 16 -1 (575 6650)(300 6650);
WIRE 16 -1 (575 6300)(575 6250);
WIRE 16 -1 (300 6300)(575 6300);
WIRE 16 -1 (575 6250)(575 6200);
WIRE 16 -1 (300 6250)(575 6250);
WIRE 16 -1 (575 6200)(575 6150);
WIRE 16 -1 (300 6200)(575 6200);
WIRE 16 -1 (300 6150)(575 6150);
WIRE 16 -1 (575 6150)(575 6100);
WIRE 16 -1 (575 6100)(575 6050);
WIRE 16 -1 (300 6100)(575 6100);
WIRE 16 -1 (575 6050)(575 5700);
WIRE 16 -1 (300 6050)(575 6050);
WIRE 16 -1 (575 5550)(575 5700);
WIRE 16 -1 (575 5700)(300 5700);
WIRE 16 -1 (575 5400)(575 5550);
WIRE 16 -1 (575 5550)(300 5550);
WIRE 16 -1 (575 5250)(575 5400);
WIRE 16 -1 (575 5400)(300 5400);
WIRE 16 -1 (575 5250)(300 5250);
WIRE 16 -1 (575 5100)(575 5250);
WIRE 16 -1 (575 5100)(575 4950);
WIRE 16 -1 (575 5100)(300 5100);
WIRE 16 -1 (575 4800)(575 4950);
WIRE 16 -1 (575 4950)(300 4950);
WIRE 16 -1 (575 4800)(575 4650);
WIRE 16 -1 (575 4800)(300 4800);
WIRE 16 -1 (575 4650)(575 4500);
WIRE 16 -1 (575 4650)(300 4650);
WIRE 16 -1 (575 4500)(575 4350);
WIRE 16 -1 (575 4500)(300 4500);
WIRE 16 -1 (575 4350)(575 4200);
WIRE 16 -1 (575 4350)(300 4350);
WIRE 16 -1 (575 4200)(300 4200);
WIRE 16 -1 (575 4200)(575 4000);
WIRE 16 -1 (575 3850)(575 4000);
WIRE 16 -1 (575 4000)(300 4000);
WIRE 16 -1 (575 3700)(575 3850);
WIRE 16 -1 (575 3850)(300 3850);
WIRE 16 -1 (575 3550)(575 3700);
WIRE 16 -1 (575 3700)(300 3700);
WIRE 16 -1 (575 3400)(575 3550);
WIRE 16 -1 (575 3550)(300 3550);
WIRE 16 -1 (575 3250)(575 3400);
WIRE 16 -1 (575 3400)(300 3400);
WIRE 16 -1 (575 3100)(575 3250);
WIRE 16 -1 (575 3250)(300 3250);
WIRE 16 -1 (575 3100)(300 3100);
WIRE 16 -1 (575 2950)(575 3100);
WIRE 16 -1 (575 2800)(575 2950);
WIRE 16 -1 (575 2950)(300 2950);
WIRE 16 -1 (575 2550)(575 2800);
WIRE 16 -1 (300 2800)(575 2800);
WIRE 16 -1 (575 2500)(575 2550);
WIRE 16 -1 (300 2550)(575 2550);
WIRE 16 -1 (575 2450)(575 2500);
WIRE 16 -1 (300 2500)(575 2500);
WIRE 16 -1 (575 2400)(575 2450);
WIRE 16 -1 (300 2450)(575 2450);
WIRE 16 -1 (575 2350)(575 2400);
WIRE 16 -1 (300 2400)(575 2400);
WIRE 16 -1 (575 2275)(575 2350);
WIRE 16 -1 (300 2350)(575 2350);
WIRE 16 -1 (1925 5800)(300 5800);
FORCEPROP 2 LAST SIG_NAME RST_PERST1_OCP_SFF_N
J 0
(665 5810);
DISPLAY 0.553191 (665 5810);
PAINT WHITE (665 5810);
WIRE 16 -1 (300 5750)(1925 5750);
FORCEPROP 2 LAST SIG_NAME OCP_SFF_PRSNT2_R_N
J 0
(665 5760);
DISPLAY 0.510638 (665 5760);
PAINT WHITE (665 5760);
WIRE 16 -1 (300 5650)(1925 5650);
FORCEPROP 2 LAST SIG_NAME CLK_100M_CPU0_CLK03_DN
J 0
(665 5660);
DISPLAY 0.680851 (665 5660);
PAINT WHITE (665 5660);
WIRE 16 -1 (1675 5950)(300 5950);
FORCEPROP 2 LAST SIG_NAME SMB_OCP_SFF_3V3AUX_BUF_R_SDA
J 0
(665 5960);
DISPLAY 0.553191 (665 5960);
PAINT WHITE (665 5960);
FORCEPROP 2 LASTPROP $XRERR UNIQUE?
J 0
(425 5960);
DISPLAY 0.638298 (425 5960);
PAINT MONO (425 5960);
DISPLAY INVISIBLE (425 5960);
WIRE 16 -1 (2325 1975)(2325 1850);
WIRE 16 -1 (2050 1975)(2325 1975);
WIRE 16 -1 (2050 1975)(2050 1850);
WIRE 16 -1 (1775 1975)(2050 1975);
WIRE 16 -1 (1775 1975)(1775 1850);
WIRE 16 -1 (1500 1975)(1775 1975);
WIRE 16 -1 (1500 1975)(1500 1850);
WIRE 16 -1 (1500 1975)(1100 1975);
WIRE 16 -1 (1100 1975)(1100 1850);
WIRE 16 -1 (825 1975)(1100 1975);
WIRE 16 -1 (825 2050)(825 1975);
WIRE 16 -1 (825 1850)(825 1975);
WIRE 16 -1 (-1425 6050)(-1000 6050);
WIRE 16 -1 (-1425 6050)(-1425 6100);
WIRE 16 -1 (-1425 6100)(-1425 6150);
WIRE 16 -1 (-1000 6100)(-1425 6100);
WIRE 16 -1 (-1000 6150)(-1425 6150);
WIRE 16 -1 (-1425 6150)(-1425 6200);
WIRE 16 -1 (-1000 6200)(-1425 6200);
WIRE 16 -1 (-1425 6200)(-1425 6250);
WIRE 16 -1 (-1000 6250)(-1425 6250);
WIRE 16 -1 (-1425 6250)(-1425 6300);
WIRE 16 -1 (-1000 6300)(-1425 6300);
WIRE 16 -1 (-1425 7350)(-1425 6300);
WIRE 16 -1 (-2250 5800)(-1000 5800);
WIRE 16 -1 (-2250 6125)(-2250 5800);
WIRE 16 -1 (-4650 4725)(-4325 4725);
WIRE 16 -1 (-4650 4725)(-4650 4625);
WIRE 16 -1 (-4325 4625)(-4650 4625);
WIRE 16 -1 (-4650 4625)(-4650 4425);
WIRE 16 -1 (-4325 4425)(-4650 4425);
WIRE 16 -1 (-4650 4425)(-4650 4375);
WIRE 16 -1 (-650 1625)(-200 1625);
WIRE 16 -1 (-200 1800)(-200 1625);
WIRE 16 -1 (-200 1800)(-200 1975);
WIRE 16 -1 (-650 1800)(-200 1800);
WIRE 16 -1 (-200 2075)(-200 1975);
WIRE 16 -1 (-650 1975)(-200 1975);
WIRE 16 -1 (-3825 2350)(-3825 2450);
WIRE 16 -1 (-3825 2450)(-4300 2450);
WIRE 16 -1 (-4300 2500)(-4300 2450);
WIRE 16 -1 (-4300 2450)(-4300 2350);
WIRE 16 -1 (-1350 6650)(-1000 6650);
WIRE 16 -1 (-1350 6500)(-1350 6650);
WIRE 16 -1 (-1350 6500)(-1000 6500);
WIRE 16 -1 (-1350 6500)(-1350 5700);
WIRE 16 -1 (-1350 5700)(-1000 5700);
WIRE 16 -1 (-1350 5550)(-1350 5700);
WIRE 16 -1 (-1350 5550)(-1000 5550);
WIRE 16 -1 (-1350 5400)(-1350 5550);
WIRE 16 -1 (-1350 5400)(-1000 5400);
WIRE 16 -1 (-1350 5400)(-1350 5250);
WIRE 16 -1 (-1350 5250)(-1000 5250);
WIRE 16 -1 (-1350 5250)(-1350 5100);
WIRE 16 -1 (-1350 5100)(-1000 5100);
WIRE 16 -1 (-1350 5100)(-1350 4950);
WIRE 16 -1 (-1350 4950)(-1000 4950);
WIRE 16 -1 (-1350 4800)(-1350 4950);
WIRE 16 -1 (-1350 4800)(-1000 4800);
WIRE 16 -1 (-1350 4650)(-1350 4800);
WIRE 16 -1 (-1350 4650)(-1000 4650);
WIRE 16 -1 (-1350 4500)(-1350 4650);
WIRE 16 -1 (-1350 4500)(-1000 4500);
WIRE 16 -1 (-1350 4500)(-1350 4350);
WIRE 16 -1 (-1350 4350)(-1000 4350);
WIRE 16 -1 (-1350 4200)(-1350 4350);
WIRE 16 -1 (-1350 4200)(-1000 4200);
WIRE 16 -1 (-1350 4200)(-1350 4000);
WIRE 16 -1 (-1350 4000)(-1000 4000);
WIRE 16 -1 (-1350 3850)(-1350 4000);
WIRE 16 -1 (-1350 3850)(-1000 3850);
WIRE 16 -1 (-1350 3700)(-1350 3850);
WIRE 16 -1 (-1350 3700)(-1000 3700);
WIRE 16 -1 (-1350 3550)(-1350 3700);
WIRE 16 -1 (-1350 3550)(-1000 3550);
WIRE 16 -1 (-1350 3400)(-1350 3550);
WIRE 16 -1 (-1350 3400)(-1000 3400);
WIRE 16 -1 (-1350 3400)(-1350 3250);
WIRE 16 -1 (-1350 3250)(-1000 3250);
WIRE 16 -1 (-1350 3250)(-1350 3100);
WIRE 16 -1 (-1350 3100)(-1000 3100);
WIRE 16 -1 (-1350 3100)(-1350 2950);
WIRE 16 -1 (-1350 2950)(-1000 2950);
WIRE 16 -1 (-1350 2950)(-1350 2800);
WIRE 16 -1 (-1350 2800)(-1000 2800);
WIRE 16 -1 (-1350 2550)(-1350 2800);
WIRE 16 -1 (-650 1450)(-200 1450);
WIRE 16 -1 (-200 1375)(-200 1450);
WIRE 16 -1 (3375 2125)(3650 2125);
WIRE 16 -1 (3100 2125)(3375 2125);
WIRE 16 -1 (3375 2125)(3375 2000);
WIRE 16 -1 (3650 2125)(3650 2000);
WIRE 16 -1 (2850 2125)(3100 2125);
WIRE 16 -1 (3100 2125)(3100 2000);
WIRE 16 -1 (2850 2200)(2850 2125);
WIRE 16 -1 (2850 2125)(2850 2000);
WIRE 16 -1 (2850 1800)(2850 1675);
WIRE 16 -1 (2850 1675)(3100 1675);
WIRE 16 -1 (3375 1675)(3100 1675);
WIRE 16 -1 (3100 1675)(3100 1800);
WIRE 16 -1 (3650 1675)(3375 1675);
WIRE 16 -1 (3375 1675)(3375 1800);
WIRE 16 -1 (3650 1675)(3650 1800);
WIRE 16 -1 (3650 1600)(3650 1675);
WIRE 16 -1 (825 1650)(825 1525);
WIRE 16 -1 (825 1525)(1100 1525);
WIRE 16 -1 (1100 1525)(1100 1650);
WIRE 16 -1 (1500 1525)(1100 1525);
WIRE 16 -1 (1500 1525)(1775 1525);
WIRE 16 -1 (1500 1525)(1500 1650);
WIRE 16 -1 (2050 1525)(1775 1525);
WIRE 16 -1 (1775 1525)(1775 1650);
WIRE 16 -1 (2050 1525)(2050 1650);
WIRE 16 -1 (2325 1525)(2050 1525);
WIRE 16 -1 (2325 1525)(2325 1650);
WIRE 16 -1 (2325 1450)(2325 1525);
WIRE 16 -1 (300 6750)(1375 6750);
FORCEPROP 2 LAST SIG_NAME NCSI_OCP_SFF_TXD1
J 0
(665 6760);
DISPLAY 0.553191 (665 6760);
PAINT WHITE (665 6760);
WIRE 16 -1 (300 6600)(1375 6600);
FORCEPROP 2 LAST SIG_NAME CLK_100M_CPU0_CLK05_DN
J 0
(615 6610);
DISPLAY 0.680851 (615 6610);
PAINT WHITE (615 6610);
WIRE 16 -1 (-2775 7050)(-1000 7050);
FORCEPROP 2 LAST SIG_NAME OCP_SFF_MAIN_PWR_EN_R
J 0
(-2210 7060);
DISPLAY 0.680851 (-2210 7060);
PAINT WHITE (-2210 7060);
FORCEPROP 2 LASTPROP $XRERR UNIQUE?
J 0
(-2450 7060);
DISPLAY 0.638298 (-2450 7060);
PAINT MONO (-2450 7060);
DISPLAY INVISIBLE (-2450 7060);
WIRE 16 -1 (-2275 7000)(-1000 7000);
FORCEPROP 2 LAST SIG_NAME SGPIO_OCP_SFF_LD_N
J 0
(-2210 7010);
DISPLAY 0.680851 (-2210 7010);
PAINT WHITE (-2210 7010);
WIRE 16 -1 (-2275 6900)(-1000 6900);
FORCEPROP 2 LAST SIG_NAME SGPIO_OCP_SFF_DATAOUT
J 0
(-2210 6910);
DISPLAY 0.680851 (-2210 6910);
PAINT WHITE (-2210 6910);
WIRE 16 -1 (-2275 6850)(-1000 6850);
FORCEPROP 2 LAST SIG_NAME SGPIO_OCP_SFF_CLK
J 0
(-2210 6860);
DISPLAY 0.680851 (-2210 6860);
PAINT WHITE (-2210 6860);
WIRE 16 -1 (-2275 6600)(-1000 6600);
FORCEPROP 2 LAST SIG_NAME CLK_100M_CPU0_CLK04_DN
J 0
(-2210 6610);
DISPLAY 0.680851 (-2210 6610);
PAINT WHITE (-2210 6610);
WIRE 16 -1 (-2275 6550)(-1000 6550);
FORCEPROP 2 LAST SIG_NAME CLK_100M_CPU0_CLK04_DP
J 0
(-2210 6560);
DISPLAY 0.680851 (-2210 6560);
PAINT WHITE (-2210 6560);
WIRE 16 -1 (-2275 6950)(-1000 6950);
FORCEPROP 2 LAST SIG_NAME SGPIO_OCP_SFF_DATAIN
J 0
(-2210 6960);
DISPLAY 0.680851 (-2210 6960);
PAINT WHITE (-2210 6960);
WIRE 16 -1 (-2275 6800)(-1000 6800);
FORCEPROP 2 LAST SIG_NAME OCP_SFF_ID0
J 0
(-2210 6810);
DISPLAY 0.680851 (-2210 6810);
PAINT WHITE (-2210 6810);
WIRE 16 -1 (-2275 6750)(-1000 6750);
FORCEPROP 2 LAST SIG_NAME NCSI_OCP_SFF_RXD1
J 0
(-2210 6760);
DISPLAY 0.680851 (-2210 6760);
PAINT WHITE (-2210 6760);
WIRE 16 -1 (-3775 5750)(-2975 5750);
FORCEPROP 2 LAST SIG_NAME OCP_SFF_AUX_PWR_EN
J 0
(-3710 5760);
DISPLAY 0.553191 (-3710 5760);
PAINT SKYBLUE (-3710 5760);
WIRE 16 -1 (-2925 4725)(-4125 4725);
FORCEPROP 0 LAST CDS_PHYS_NET_NAME OCP_SFF_AUX_PWR_EN
J 0
(-3760 4767);
PAINT MONO (-3760 4767);
DISPLAY INVISIBLE (-3760 4767);
FORCEPROP 2 LAST SIG_NAME OCP_SFF_AUX_PWR_EN
J 0
(-3685 4735);
DISPLAY 0.680851 (-3685 4735);
PAINT SKYBLUE (-3685 4735);
WIRE 16 -1 (300 5150)(725 5150);
WIRE 16 -1 (300 5200)(875 5200);
WIRE 16 -1 (300 5600)(1925 5600);
FORCEPROP 2 LAST SIG_NAME CLK_100M_CPU0_CLK03_DP
J 0
(665 5610);
DISPLAY 0.680851 (665 5610);
PAINT WHITE (665 5610);
WIRE 16 -1 (300 5450)(725 5450);
WIRE 16 -1 (300 5350)(875 5350);
WIRE 16 -1 (-2725 5600)(-1000 5600);
FORCEPROP 2 LAST SIG_NAME CLK_100M_CPU0_CLK02_DP
J 0
(-2660 5610);
DISPLAY 0.680851 (-2660 5610);
PAINT WHITE (-2660 5610);
WIRE 16 -1 (-1000 5750)(-2775 5750);
FORCEPROP 2 LAST SIG_NAME OCP_SFF_AUX_PWR_EN_R
J 0
(-2160 5760);
DISPLAY 0.553191 (-2160 5760);
PAINT SKYBLUE (-2160 5760);
FORCEPROP 2 LASTPROP $XRERR UNIQUE?
J 0
(-2400 5760);
DISPLAY 0.638298 (-2400 5760);
PAINT MONO (-2400 5760);
DISPLAY INVISIBLE (-2400 5760);
WIRE 16 -1 (-2925 4625)(-4125 4625);
FORCEPROP 0 LAST CDS_PHYS_NET_NAME OCP_SFF_MAIN_PWR_EN
J 0
(-3760 4667);
PAINT MONO (-3760 4667);
DISPLAY INVISIBLE (-3760 4667);
FORCEPROP 2 LAST SIG_NAME OCP_SFF_MAIN_PWR_EN
J 0
(-3685 4635);
DISPLAY 0.680851 (-3685 4635);
PAINT WHITE (-3685 4635);
WIRE 16 -1 (-2925 4425)(-4125 4425);
FORCEPROP 0 LAST CDS_PHYS_NET_NAME FM_OCP_SFF_PWR_GOOD
J 0
(-3760 4467);
PAINT MONO (-3760 4467);
DISPLAY INVISIBLE (-3760 4467);
FORCEPROP 2 LAST SIG_NAME FM_OCP_SFF_PWR_GOOD
J 0
(-3685 4435);
DISPLAY 0.680851 (-3685 4435);
PAINT WHITE (-3685 4435);
WIRE 16 -1 (-3775 5850)(-1000 5850);
FORCEPROP 2 LAST SIG_NAME RST_PERST0_OCP_SFF_N
J 0
(-2160 5860);
DISPLAY 0.553191 (-2160 5860);
PAINT WHITE (-2160 5860);
WIRE 16 -1 (-2775 5900)(-1000 5900);
FORCEPROP 2 LAST SIG_NAME OCP_SFF_BIF2_R_N
J 0
(-2160 5910);
DISPLAY 0.553191 (-2160 5910);
PAINT WHITE (-2160 5910);
FORCEPROP 2 LASTPROP $XRERR UNIQUE?
J 0
(-2400 5910);
DISPLAY 0.638298 (-2400 5910);
PAINT MONO (-2400 5910);
DISPLAY INVISIBLE (-2400 5910);
WIRE 16 -1 (-2775 5950)(-1000 5950);
FORCEPROP 2 LAST SIG_NAME OCP_SFF_BIF1_R_N
J 0
(-2160 5960);
DISPLAY 0.553191 (-2160 5960);
PAINT WHITE (-2160 5960);
FORCEPROP 2 LASTPROP $XRERR UNIQUE?
J 0
(-2400 5960);
DISPLAY 0.638298 (-2400 5960);
PAINT MONO (-2400 5960);
DISPLAY INVISIBLE (-2400 5960);
WIRE 16 -1 (-2775 6000)(-1000 6000);
FORCEPROP 2 LAST SIG_NAME OCP_SFF_BIF0_R_N
J 0
(-2160 6010);
DISPLAY 0.553191 (-2160 6010);
PAINT WHITE (-2160 6010);
FORCEPROP 2 LASTPROP $XRERR UNIQUE?
J 0
(-2400 6010);
DISPLAY 0.638298 (-2400 6010);
PAINT MONO (-2400 6010);
DISPLAY INVISIBLE (-2400 6010);
WIRE 16 -1 (-2725 5650)(-1000 5650);
FORCEPROP 2 LAST SIG_NAME CLK_100M_CPU0_CLK02_DN
J 0
(-2660 5660);
DISPLAY 0.680851 (-2660 5660);
PAINT WHITE (-2660 5660);
WIRE 16 -1 (-1000 4150)(-2725 4150);
FORCEPROP 2 LAST SIG_NAME OCP_SFF_PRSNT0_R_N
J 0
(-2660 4160);
DISPLAY 0.680851 (-2660 4160);
PAINT WHITE (-2660 4160);
WIRE 16 -1 (-4300 2000)(-3275 2000);
FORCEPROP 2 LAST SIG_NAME OCP_SFF_ID0
J 0
(-3710 2010);
DISPLAY 0.680851 (-3710 2010);
PAINT WHITE (-3710 2010);
WIRE 16 -1 (-4300 2000)(-4300 2150);
WIRE 16 -1 (-4300 1825)(-4300 2000);
WIRE 16 -1 (-3825 2150)(-3825 1950);
WIRE 16 -1 (-3825 1950)(-3275 1950);
FORCEPROP 2 LAST SIG_NAME OCP_SFF_ID1
J 0
(-3710 1960);
DISPLAY 0.680851 (-3710 1960);
PAINT WHITE (-3710 1960);
WIRE 16 -1 (-3825 1825)(-3825 1950);
WIRE 16 -1 (-2725 2650)(-1000 2650);
FORCEPROP 2 LAST SIG_NAME OCP_SFF_PRSNT3_R_N
J 0
(-2660 2660);
DISPLAY 0.680851 (-2660 2660);
PAINT WHITE (-2660 2660);
WIRE 16 -1 (-2725 2750)(-1000 2750);
FORCEPROP 2 LAST SIG_NAME TP_OCP_SFF_B68
J 0
(-2660 2760);
DISPLAY 0.680851 (-2660 2760);
PAINT WHITE (-2660 2760);
FORCEPROP 2 LASTPROP $XRERR UNIQUE?
J 0
(-2965 2750);
DISPLAY 0.638298 (-2965 2750);
PAINT MONO (-2965 2750);
DISPLAY INVISIBLE (-2965 2750);
WIRE 16 -1 (-2725 2700)(-1000 2700);
FORCEPROP 2 LAST SIG_NAME TP_OCP_SFF_B69
J 0
(-2660 2710);
DISPLAY 0.680851 (-2660 2710);
PAINT WHITE (-2660 2710);
FORCEPROP 2 LASTPROP $XRERR UNIQUE?
J 0
(-2965 2700);
DISPLAY 0.638298 (-2965 2700);
PAINT MONO (-2965 2700);
DISPLAY INVISIBLE (-2965 2700);
WIRE 16 -1 (-1950 1800)(-850 1800);
FORCEPROP 2 LAST SIG_NAME SGPIO_OCP_SFF_DATAIN
J 0
(-1835 1810);
DISPLAY 0.680851 (-1835 1810);
PAINT WHITE (-1835 1810);
WIRE 16 -1 (-1950 1625)(-850 1625);
FORCEPROP 2 LAST SIG_NAME SGPIO_OCP_SFF_CLK
J 0
(-1835 1635);
DISPLAY 0.680851 (-1835 1635);
PAINT WHITE (-1835 1635);
WIRE 16 -1 (-1925 1450)(-850 1450);
FORCEPROP 2 LAST SIG_NAME SGPIO_OCP_SFF_DATAOUT
J 0
(-1810 1460);
DISPLAY 0.680851 (-1810 1460);
PAINT WHITE (-1810 1460);
WIRE 16 -1 (-1950 1975)(-850 1975);
FORCEPROP 2 LAST SIG_NAME SGPIO_OCP_SFF_LD_N
J 0
(-1835 1985);
DISPLAY 0.680851 (-1835 1985);
PAINT WHITE (-1835 1985);
WIRE 16 -1 (-1675 3000)(-1000 3000);
WIRE 16 -1 (-1525 3050)(-1000 3050);
WIRE 16 -1 (-1525 2900)(-1000 2900);
WIRE 16 -1 (-1000 2850)(-1675 2850);
WIRE 16 -1 (-1675 3150)(-1000 3150);
WIRE 16 -1 (-1675 3450)(-1000 3450);
WIRE 16 -1 (-1675 3600)(-1000 3600);
WIRE 16 -1 (-1525 3500)(-1000 3500);
WIRE 16 -1 (-1675 3750)(-1000 3750);
WIRE 16 -1 (-1525 3800)(-1000 3800);
WIRE 16 -1 (-1525 3950)(-1000 3950);
WIRE 16 -1 (-1525 3650)(-1000 3650);
WIRE 16 -1 (-1525 3350)(-1000 3350);
WIRE 16 -1 (-1525 3200)(-1000 3200);
WIRE 16 -1 (-3775 5900)(-2975 5900);
FORCEPROP 2 LAST SIG_NAME OCP_SFF_ISO_BIF2_EN
J 0
(-3710 5910);
DISPLAY 0.553191 (-3710 5910);
PAINT WHITE (-3710 5910);
WIRE 16 -1 (-3775 6000)(-2975 6000);
FORCEPROP 2 LAST SIG_NAME OCP_SFF_ISO_BIF0_EN
J 0
(-3710 6010);
DISPLAY 0.553191 (-3710 6010);
PAINT WHITE (-3710 6010);
WIRE 16 -1 (-3775 5950)(-2975 5950);
FORCEPROP 2 LAST SIG_NAME OCP_SFF_ISO_BIF1_EN
J 0
(-3710 5960);
DISPLAY 0.553191 (-3710 5960);
PAINT WHITE (-3710 5960);
WIRE 16 -1 (-1525 4600)(-1000 4600);
WIRE 16 -1 (-1525 4750)(-1000 4750);
WIRE 16 -1 (-1525 4300)(-1000 4300);
WIRE 16 -1 (-1525 4450)(-1000 4450);
WIRE 16 -1 (-1675 4550)(-1000 4550);
WIRE 16 -1 (-1675 5000)(-1000 5000);
WIRE 16 -1 (-1525 5050)(-1000 5050);
WIRE 16 -1 (300 3600)(725 3600);
WIRE 16 -1 (300 3300)(725 3300);
WIRE 16 -1 (300 3350)(875 3350);
WIRE 16 -1 (300 3450)(725 3450);
WIRE 16 -1 (300 3800)(875 3800);
WIRE 16 -1 (300 3900)(725 3900);
WIRE 16 -1 (875 3950)(300 3950);
WIRE 16 -1 (875 5050)(300 5050);
WIRE 16 -1 (300 4600)(875 4600);
WIRE 16 -1 (300 4250)(725 4250);
WIRE 16 -1 (300 4300)(875 4300);
WIRE 16 -1 (300 4550)(725 4550);
WIRE 16 -1 (300 4700)(725 4700);
WIRE 16 -1 (300 4750)(875 4750);
WIRE 16 -1 (300 5500)(875 5500);
WIRE 16 -1 (300 5300)(725 5300);
WIRE 16 -1 (300 6700)(1375 6700);
FORCEPROP 2 LAST SIG_NAME NCSI_OCP_SFF_TXD0
J 0
(665 6710);
DISPLAY 0.553191 (665 6710);
PAINT WHITE (665 6710);
WIRE 16 -1 (300 3000)(725 3000);
WIRE 16 -1 (-1675 3300)(-1000 3300);
WIRE 16 -1 (300 6800)(1375 6800);
FORCEPROP 2 LAST SIG_NAME NCSI_OCP_SFF_TX_EN
J 0
(665 6810);
DISPLAY 0.553191 (665 6810);
PAINT WHITE (665 6810);
WIRE 16 -1 (300 4400)(725 4400);
WIRE 16 -1 (300 4450)(875 4450);
WIRE 16 -1 (300 3150)(725 3150);
WIRE 16 -1 (300 3050)(875 3050);
WIRE 16 -1 (300 4150)(1925 4150);
FORCEPROP 2 LAST SIG_NAME OCP_SFF_PRSNT1_R_N
J 0
(1015 4160);
DISPLAY 0.638298 (1015 4160);
PAINT WHITE (1015 4160);
WIRE 16 -1 (300 5000)(725 5000);
WIRE 16 -1 (-1000 6450)(-2275 6450);
FORCEPROP 2 LAST SIG_NAME NCSI_OCP_SFF_CRS_DV
J 0
(-2210 6460);
DISPLAY 0.680851 (-2210 6460);
PAINT WHITE (-2210 6460);
WIRE 16 -1 (-2275 6700)(-1000 6700);
FORCEPROP 2 LAST SIG_NAME NCSI_OCP_SFF_RXD0
J 0
(-2210 6710);
DISPLAY 0.680851 (-2210 6710);
PAINT WHITE (-2210 6710);
WIRE 16 -1 (-1675 3900)(-1000 3900);
WIRE 16 -1 (-1675 4250)(-1000 4250);
WIRE 16 -1 (-1675 4400)(-1000 4400);
WIRE 16 -1 (-1675 4700)(-1000 4700);
WIRE 16 -1 (-1525 5350)(-1000 5350);
WIRE 16 -1 (-1675 5300)(-1000 5300);
WIRE 16 -1 (-1525 5200)(-1000 5200);
WIRE 16 -1 (-1675 5150)(-1000 5150);
WIRE 16 -1 (-1525 5500)(-1000 5500);
WIRE 16 -1 (-1675 5450)(-1000 5450);
WIRE 16 -1 (300 2850)(725 2850);
WIRE 16 -1 (300 2700)(1425 2700);
FORCEPROP 2 LAST SIG_NAME USB2_P11_DP
J 0
(615 2710);
DISPLAY 0.638298 (615 2710);
PAINT WHITE (615 2710);
FORCEPROP 2 LASTPROP $XRERR UNIQUE?
J 0
(375 2710);
DISPLAY 0.638298 (375 2710);
PAINT MONO (375 2710);
DISPLAY INVISIBLE (375 2710);
WIRE 16 -1 (300 3750)(725 3750);
WIRE 16 -1 (1625 2750)(2675 2750);
FORCEPROP 2 LAST SIG_NAME USB2_CPU0_P11_DN
J 0
(2140 2760);
DISPLAY 0.638298 (2140 2760);
PAINT WHITE (2140 2760);
WIRE 16 -1 (2675 2700)(1625 2700);
FORCEPROP 2 LAST SIG_NAME USB2_CPU0_P11_DP
J 0
(2140 2710);
DISPLAY 0.638298 (2140 2710);
PAINT WHITE (2140 2710);
WIRE 16 -1 (300 2900)(875 2900);
WIRE 16 -1 (300 2650)(1125 2650);
FORCEPROP 2 LAST SIG_NAME OCP_SFF_PWRBRK_N
J 0
(615 2660);
DISPLAY 0.638298 (615 2660);
PAINT WHITE (615 2660);
WIRE 16 -1 (875 3500)(300 3500);
WIRE 16 -1 (300 3650)(875 3650);
WIRE 16 -1 (300 2750)(1425 2750);
FORCEPROP 2 LAST SIG_NAME USB2_P11_DN
J 0
(615 2760);
DISPLAY 0.638298 (615 2760);
PAINT WHITE (615 2760);
FORCEPROP 2 LASTPROP $XRERR UNIQUE?
J 0
(375 2760);
DISPLAY 0.638298 (375 2760);
PAINT MONO (375 2760);
DISPLAY INVISIBLE (375 2760);
WIRE 16 -1 (300 3200)(875 3200);
WIRE 16 -1 (1375 7050)(300 7050);
FORCEPROP 2 LAST SIG_NAME RST_PERST3_OCP_SFF_N
J 0
(665 7060);
DISPLAY 0.553191 (665 7060);
PAINT WHITE (665 7060);
WIRE 16 -1 (300 7000)(1375 7000);
FORCEPROP 2 LAST SIG_NAME IRQ_LVC3_OCP_SFF_WAKE_N
J 0
(665 7010);
DISPLAY 0.553191 (665 7010);
PAINT WHITE (665 7010);
WIRE 16 -1 (300 6950)(1375 6950);
FORCEPROP 2 LAST SIG_NAME OCP_SFF_ISO1_RBT_ARB_IN
J 0
(665 6960);
DISPLAY 0.553191 (665 6960);
PAINT WHITE (665 6960);
WIRE 16 -1 (300 6850)(1375 6850);
FORCEPROP 2 LAST SIG_NAME OCP_SFF_ID1
J 0
(665 6860);
DISPLAY 0.553191 (665 6860);
PAINT WHITE (665 6860);
WIRE 16 -1 (300 6900)(1375 6900);
FORCEPROP 2 LAST SIG_NAME OCP_SFF_ISO2_RBT_ARB_OUT
J 0
(665 6910);
DISPLAY 0.553191 (665 6910);
PAINT WHITE (665 6910);
WIRE 16 -1 (1375 7100)(300 7100);
FORCEPROP 2 LAST SIG_NAME RST_PERST2_OCP_SFF_N
J 0
(665 7110);
DISPLAY 0.553191 (665 7110);
PAINT WHITE (665 7110);
DOT 1 (-4650 4625);
DOT 1 (-4300 2000);
DOT 1 (-4300 2450);
DOT 1 (-4650 4425);
DOT 1 (-3825 1950);
DOT 1 (-200 1800);
DOT 1 (-200 1975);
DOT 1 (-1350 2800);
DOT 1 (-1350 2950);
DOT 1 (-1350 3250);
DOT 1 (-1350 3100);
DOT 1 (-1350 3400);
DOT 1 (-1350 3550);
DOT 1 (-1350 3700);
DOT 1 (-1350 3850);
DOT 1 (-1350 4000);
DOT 1 (-1350 4350);
DOT 1 (-1350 4200);
DOT 1 (-1350 4500);
DOT 1 (-1350 4800);
DOT 1 (-1350 4650);
DOT 1 (-1350 4950);
DOT 1 (-1350 5100);
DOT 1 (-1350 5250);
DOT 1 (-1350 5400);
DOT 1 (-1350 5550);
DOT 1 (-1350 5700);
DOT 1 (-1425 6100);
DOT 1 (-1425 6150);
DOT 1 (-1425 6200);
DOT 1 (-1425 6250);
DOT 1 (-1425 6300);
DOT 1 (-1350 6500);
DOT 1 (825 1975);
DOT 1 (1100 1525);
DOT 1 (1500 1525);
DOT 1 (1100 1975);
DOT 1 (1500 1975);
DOT 1 (1775 1525);
DOT 1 (2050 1525);
DOT 1 (1775 1975);
DOT 1 (2050 1975);
DOT 1 (575 2350);
DOT 1 (575 2400);
DOT 1 (575 2450);
DOT 1 (575 2500);
DOT 1 (575 2550);
DOT 1 (575 2800);
DOT 1 (575 2950);
DOT 1 (575 3250);
DOT 1 (575 3550);
DOT 1 (575 3400);
DOT 1 (575 3700);
DOT 1 (575 3850);
DOT 1 (575 4000);
DOT 1 (2325 1525);
DOT 1 (3100 1675);
DOT 1 (3375 1675);
DOT 1 (3650 1675);
DOT 1 (2850 2125);
DOT 1 (3100 2125);
DOT 1 (3375 2125);
DOT 1 (575 4350);
DOT 1 (575 4200);
DOT 1 (575 4500);
DOT 1 (575 4800);
DOT 1 (575 4650);
DOT 1 (575 5100);
DOT 1 (575 4950);
DOT 1 (575 5250);
DOT 1 (575 5550);
DOT 1 (575 5400);
DOT 1 (575 5700);
DOT 1 (575 6050);
DOT 1 (575 6100);
DOT 1 (575 6150);
DOT 1 (575 6200);
DOT 1 (575 6250);
DOT 1 (575 6300);
DOT 1 (575 6500);
DOT 1 (575 3100);
FORCENOTE
FROM CPU0 PCIE G3 [15:0]
(-4550 5475) 0;
DISPLAY LEFT (-4550 5475);
DISPLAY 1.276596 (-4550 5475);
PAINT SKYBLUE (-4550 5475);
FORCENOTE
TO CPU0 PCIE G3 [15:0]
(1075 5350) 0;
DISPLAY LEFT (1075 5350);
DISPLAY 1.276596 (1075 5350);
PAINT SKYBLUE (1075 5350);
FORCENOTE
P/N SWAP
(-2175 5400) 0;
DISPLAY LEFT (-2175 5400);
DISPLAY 1.021277 (-2175 5400);
FORCENOTE
P/N SWAP
(-2150 5300) 0;
DISPLAY LEFT (-2150 5300);
DISPLAY 1.021277 (-2150 5300);
FORCENOTE
P/N SWAP
(-2175 5150) 0;
DISPLAY LEFT (-2175 5150);
DISPLAY 1.021277 (-2175 5150);
FORCENOTE
P/N SWAP
(-2200 5000) 0;
DISPLAY LEFT (-2200 5000);
DISPLAY 1.021277 (-2200 5000);
FORCENOTE
P/N SWAP
(-2200 4700) 0;
DISPLAY LEFT (-2200 4700);
DISPLAY 1.021277 (-2200 4700);
FORCENOTE
P/N SWAP
(-2200 4550) 0;
DISPLAY LEFT (-2200 4550);
DISPLAY 1.021277 (-2200 4550);
FORCENOTE
P/N SWAP
(-2175 4400) 0;
DISPLAY LEFT (-2175 4400);
DISPLAY 1.021277 (-2175 4400);
FORCENOTE
P/N SWAP
(-2175 4250) 0;
DISPLAY LEFT (-2175 4250);
DISPLAY 1.021277 (-2175 4250);
FORCENOTE
P/N SWAP
(-2175 3900) 0;
DISPLAY LEFT (-2175 3900);
DISPLAY 1.021277 (-2175 3900);
FORCENOTE
P/N SWAP
(-2200 3750) 0;
DISPLAY LEFT (-2200 3750);
DISPLAY 1.021277 (-2200 3750);
FORCENOTE
P/N SWAP
(-2225 3600) 0;
DISPLAY LEFT (-2225 3600);
DISPLAY 1.021277 (-2225 3600);
FORCENOTE
P/N SWAP
(-2200 3450) 0;
DISPLAY LEFT (-2200 3450);
DISPLAY 1.021277 (-2200 3450);
FORCENOTE
P/N SWAP
(-2200 3300) 0;
DISPLAY LEFT (-2200 3300);
DISPLAY 1.021277 (-2200 3300);
FORCENOTE
P/N SWAP
(-2200 3150) 0;
DISPLAY LEFT (-2200 3150);
DISPLAY 1.021277 (-2200 3150);
FORCENOTE
P/N SWAP
(-2200 3000) 0;
DISPLAY LEFT (-2200 3000);
DISPLAY 1.021277 (-2200 3000);
FORCENOTE
P/N SWAP
(-2175 2850) 0;
DISPLAY LEFT (-2175 2850);
DISPLAY 1.021277 (-2175 2850);
QUIT
